FILE_TYPE = MACRO_DRAWING;
SET COLOR_WIRE YELLOW;
SET COLOR_PROP ORANGE;
SET COLOR_DOT WHITE;
SET COLOR_ARC YELLOW;
SET COLOR_BODY GREEN;
SET COLOR_NOTE PURPLE;
SET PROP_DISPLAY VALUE;
SET PAGE_NUMBER P87;
FORCEADD GND..1
(-2300 2300);
FORCEPROP 3 LASTPIN (-2300 2350) SIG_NAME GND\g
J 0
(-2290 2360);
DISPLAY 0.659574 (-2290 2360);
PAINT MONO (-2290 2360);
DISPLAY INVISIBLE (-2290 2360);
FORCEPROP 1 LAST SIZE 1B
J 0
(-2225 2250);
DISPLAY 0.851064 (-2225 2250);
PAINT GREEN (-2225 2250);
DISPLAY INVISIBLE (-2225 2250);
FORCEPROP 2 LAST CDS_LIB mstr_symbols
J 0
(-2300 2300);
DISPLAY 0.723404 (-2300 2300);
DISPLAY INVISIBLE (-2300 2300);
FORCEPROP 1 LAST BODY_TYPE PLUMBING
J 0
(-2345 2257);
DISPLAY 0.340426 (-2345 2257);
PAINT GREEN (-2345 2257);
DISPLAY INVISIBLE (-2345 2257);
FORCEPROP 1 LAST PATH I150
J 0
(-2225 2300);
DISPLAY 0.872340 (-2225 2300);
PAINT GREEN (-2225 2300);
DISPLAY INVISIBLE (-2225 2300);
FORCEPROP 1 LAST VOLTAGE 0.0
J 0
(-2345 2257);
DISPLAY 0.723404 (-2345 2257);
PAINT SKYBLUE (-2345 2257);
DISPLAY INVISIBLE (-2345 2257);
FORCEPROP 1 LAST HDL_POWER GND
J 0
(-2300 2450);
DISPLAY 0.851064 (-2300 2450);
PAINT GREEN (-2300 2450);
DISPLAY INVISIBLE (-2300 2450);
FORCEADD GND..1
(-500 2100);
FORCEPROP 3 LASTPIN (-500 2150) SIG_NAME GND\g
J 0
(-490 2160);
DISPLAY 0.659574 (-490 2160);
PAINT MONO (-490 2160);
DISPLAY INVISIBLE (-490 2160);
FORCEPROP 2 LAST CDS_LIB mstr_symbols
J 0
(-500 2100);
DISPLAY 0.723404 (-500 2100);
DISPLAY INVISIBLE (-500 2100);
FORCEPROP 1 LAST SIZE 1B
J 0
(-425 2050);
DISPLAY 0.851064 (-425 2050);
PAINT GREEN (-425 2050);
DISPLAY INVISIBLE (-425 2050);
FORCEPROP 1 LAST BODY_TYPE PLUMBING
J 0
(-545 2057);
DISPLAY 0.340426 (-545 2057);
PAINT GREEN (-545 2057);
DISPLAY INVISIBLE (-545 2057);
FORCEPROP 1 LAST PATH I152
J 0
(-425 2100);
DISPLAY 0.872340 (-425 2100);
PAINT GREEN (-425 2100);
DISPLAY INVISIBLE (-425 2100);
FORCEPROP 1 LAST VOLTAGE 0.0
J 0
(-545 2057);
DISPLAY 0.723404 (-545 2057);
PAINT SKYBLUE (-545 2057);
DISPLAY INVISIBLE (-545 2057);
FORCEPROP 1 LAST HDL_POWER GND
J 0
(-500 2250);
DISPLAY 0.851064 (-500 2250);
PAINT GREEN (-500 2250);
DISPLAY INVISIBLE (-500 2250);
FORCEADD OFFPAGE..5
(-8525 2275);
FORCEPROP 2 LAST $XR0 12 
J 0
(-8779 2275);
DISPLAY 0.638298 (-8779 2275);
PAINT MONO (-8779 2275);
FORCEPROP 2 LAST PATH I167
J 0
(-8475 2350);
DISPLAY 0.808511 (-8475 2350);
DISPLAY INVISIBLE (-8475 2350);
FORCEPROP 1 LAST COMMENT_BODY TRUE
J 0
(-8425 2200);
DISPLAY 0.872340 (-8425 2200);
PAINT GREEN (-8425 2200);
DISPLAY INVISIBLE (-8425 2200);
FORCEPROP 1 LAST OFFPAGE TRUE
J 0
(-8200 2150);
DISPLAY 0.872340 (-8200 2150);
PAINT GREEN (-8200 2150);
DISPLAY INVISIBLE (-8200 2150);
FORCEPROP 2 LAST CDS_LIB mstr_standard
J 0
(-8525 2275);
DISPLAY 0.808511 (-8525 2275);
DISPLAY INVISIBLE (-8525 2275);
FORCEADD OFFPAGE..5
(-8525 2325);
FORCEPROP 2 LAST $XR0 12 
J 0
(-8779 2325);
DISPLAY 0.638298 (-8779 2325);
PAINT MONO (-8779 2325);
FORCEPROP 2 LAST PATH I168
J 0
(-8475 2400);
DISPLAY 0.808511 (-8475 2400);
DISPLAY INVISIBLE (-8475 2400);
FORCEPROP 1 LAST COMMENT_BODY TRUE
J 0
(-8425 2250);
DISPLAY 0.872340 (-8425 2250);
PAINT GREEN (-8425 2250);
DISPLAY INVISIBLE (-8425 2250);
FORCEPROP 1 LAST OFFPAGE TRUE
J 0
(-8200 2200);
DISPLAY 0.872340 (-8200 2200);
PAINT GREEN (-8200 2200);
DISPLAY INVISIBLE (-8200 2200);
FORCEPROP 2 LAST CDS_LIB mstr_standard
J 0
(-8525 2325);
DISPLAY 0.808511 (-8525 2325);
DISPLAY INVISIBLE (-8525 2325);
FORCEADD OFFPAGE..6
(-8525 3925);
FORCEPROP 2 LAST $XR0 12 
J 0
(-8774 3925);
DISPLAY 0.638298 (-8774 3925);
PAINT MONO (-8774 3925);
FORCEPROP 2 LAST PATH I174
J 0
(-8475 4000);
DISPLAY 0.808511 (-8475 4000);
DISPLAY INVISIBLE (-8475 4000);
FORCEPROP 1 LAST COMMENT_BODY TRUE
J 0
(-8425 3850);
DISPLAY 0.872340 (-8425 3850);
PAINT GREEN (-8425 3850);
DISPLAY INVISIBLE (-8425 3850);
FORCEPROP 1 LAST OFFPAGE TRUE
J 0
(-8200 3800);
DISPLAY 0.872340 (-8200 3800);
PAINT GREEN (-8200 3800);
DISPLAY INVISIBLE (-8200 3800);
FORCEPROP 2 LAST CDS_LIB mstr_standard
J 0
(-8525 3925);
DISPLAY 0.723404 (-8525 3925);
PAINT MONO (-8525 3925);
DISPLAY INVISIBLE (-8525 3925);
FORCEADD OFFPAGE..1
(-8525 3425);
FORCEPROP 2 LAST $XR0 12 
J 0
(-8746 3425);
DISPLAY 0.638298 (-8746 3425);
PAINT MONO (-8746 3425);
FORCEPROP 2 LAST PATH I176
J 0
(-8725 3650);
DISPLAY 0.808511 (-8725 3650);
DISPLAY INVISIBLE (-8725 3650);
FORCEPROP 1 LAST COMMENT_BODY TRUE
J 0
(-8400 3325);
DISPLAY 0.872340 (-8400 3325);
PAINT GREEN (-8400 3325);
DISPLAY INVISIBLE (-8400 3325);
FORCEPROP 1 LAST OFFPAGE TRUE
J 0
(-8200 3300);
DISPLAY 0.872340 (-8200 3300);
PAINT GREEN (-8200 3300);
DISPLAY INVISIBLE (-8200 3300);
FORCEPROP 2 LAST CDS_LIB mstr_standard
J 0
(-8525 3425);
DISPLAY 0.808511 (-8525 3425);
DISPLAY INVISIBLE (-8525 3425);
FORCEADD VCC_CORE..1
(-8800 3775);
FORCEPROP 3 LASTPIN (-8800 3725) SIG_NAME P3V3_STBY\g
J 0
(-8790 3735);
DISPLAY 0.659574 (-8790 3735);
PAINT MONO (-8790 3735);
DISPLAY INVISIBLE (-8790 3735);
FORCEPROP 1 LAST HDL_POWER P3V3_STBY
J 1
(-8800 3825);
DISPLAY 0.489362 (-8800 3825);
PAINT GREEN (-8800 3825);
FORCEPROP 2 LAST CDS_LIB mstr_symbols
J 0
(-8800 3775);
PAINT MONO (-8800 3775);
DISPLAY INVISIBLE (-8800 3775);
FORCEPROP 1 LAST PATH I177
J 0
(-8750 3800);
DISPLAY 0.872340 (-8750 3800);
PAINT GREEN (-8750 3800);
DISPLAY INVISIBLE (-8750 3800);
FORCEPROP 0 LAST VOLTAGE 3.3
J 0
(-9075 3925);
DISPLAY 1.021277 (-9075 3925);
PAINT SKYBLUE (-9075 3925);
DISPLAY INVISIBLE (-9075 3925);
FORCEPROP 2 LAST ROOM PVCCINFAON_CPU0_CTRL
J 0
(-8800 3875);
DISPLAY 0.808511 (-8800 3875);
PAINT RED (-8800 3875);
DISPLAY INVISIBLE (-8800 3875);
FORCEADD OFFPAGE..1
(-8525 4425);
FORCEPROP 2 LAST $XR0 12 
J 0
(-8746 4425);
DISPLAY 0.638298 (-8746 4425);
PAINT MONO (-8746 4425);
FORCEPROP 2 LAST PATH I178
J 0
(-8475 4500);
DISPLAY 0.808511 (-8475 4500);
DISPLAY INVISIBLE (-8475 4500);
FORCEPROP 1 LAST COMMENT_BODY TRUE
J 0
(-8400 4325);
DISPLAY 0.872340 (-8400 4325);
PAINT GREEN (-8400 4325);
DISPLAY INVISIBLE (-8400 4325);
FORCEPROP 1 LAST OFFPAGE TRUE
J 0
(-8200 4300);
DISPLAY 0.872340 (-8200 4300);
PAINT GREEN (-8200 4300);
DISPLAY INVISIBLE (-8200 4300);
FORCEPROP 2 LAST CDS_LIB mstr_standard
J 0
(-8525 4425);
DISPLAY 0.808511 (-8525 4425);
DISPLAY INVISIBLE (-8525 4425);
FORCEADD OFFPAGE..6
(-8525 4375);
FORCEPROP 2 LAST $XR0 12 
J 0
(-8774 4375);
DISPLAY 0.638298 (-8774 4375);
PAINT MONO (-8774 4375);
FORCEPROP 2 LAST PATH I179
J 0
(-8475 4450);
DISPLAY 0.808511 (-8475 4450);
DISPLAY INVISIBLE (-8475 4450);
FORCEPROP 1 LAST COMMENT_BODY TRUE
J 0
(-8425 4300);
DISPLAY 0.872340 (-8425 4300);
PAINT GREEN (-8425 4300);
DISPLAY INVISIBLE (-8425 4300);
FORCEPROP 1 LAST OFFPAGE TRUE
J 0
(-8200 4250);
DISPLAY 0.872340 (-8200 4250);
PAINT GREEN (-8200 4250);
DISPLAY INVISIBLE (-8200 4250);
FORCEPROP 2 LAST CDS_LIB mstr_standard
J 0
(-8525 4375);
DISPLAY 0.723404 (-8525 4375);
PAINT MONO (-8525 4375);
DISPLAY INVISIBLE (-8525 4375);
FORCEADD OFFPAGE..1
(-8525 4475);
FORCEPROP 2 LAST $XR0 12 
J 0
(-8746 4475);
DISPLAY 0.638298 (-8746 4475);
PAINT MONO (-8746 4475);
FORCEPROP 2 LAST PATH I180
J 0
(-8475 4550);
DISPLAY 0.808511 (-8475 4550);
DISPLAY INVISIBLE (-8475 4550);
FORCEPROP 1 LAST COMMENT_BODY TRUE
J 0
(-8400 4375);
DISPLAY 0.872340 (-8400 4375);
PAINT GREEN (-8400 4375);
DISPLAY INVISIBLE (-8400 4375);
FORCEPROP 1 LAST OFFPAGE TRUE
J 0
(-8200 4350);
DISPLAY 0.872340 (-8200 4350);
PAINT GREEN (-8200 4350);
DISPLAY INVISIBLE (-8200 4350);
FORCEPROP 2 LAST CDS_LIB mstr_standard
J 0
(-8525 4475);
DISPLAY 0.723404 (-8525 4475);
PAINT MONO (-8525 4475);
DISPLAY INVISIBLE (-8525 4475);
FORCEADD OFFPAGE..1
(-8525 4575);
FORCEPROP 2 LAST $XR0 12 
J 0
(-8746 4575);
DISPLAY 0.638298 (-8746 4575);
PAINT MONO (-8746 4575);
FORCEPROP 2 LAST PATH I181
J 0
(-8475 4650);
DISPLAY 0.808511 (-8475 4650);
DISPLAY INVISIBLE (-8475 4650);
FORCEPROP 1 LAST COMMENT_BODY TRUE
J 0
(-8400 4475);
DISPLAY 0.872340 (-8400 4475);
PAINT GREEN (-8400 4475);
DISPLAY INVISIBLE (-8400 4475);
FORCEPROP 1 LAST OFFPAGE TRUE
J 0
(-8200 4450);
DISPLAY 0.872340 (-8200 4450);
PAINT GREEN (-8200 4450);
DISPLAY INVISIBLE (-8200 4450);
FORCEPROP 2 LAST CDS_LIB mstr_standard
J 0
(-8525 4575);
DISPLAY 0.808511 (-8525 4575);
DISPLAY INVISIBLE (-8525 4575);
FORCEADD OFFPAGE..1
(-8525 4625);
FORCEPROP 2 LAST $XR0 12 
J 0
(-8746 4625);
DISPLAY 0.638298 (-8746 4625);
PAINT MONO (-8746 4625);
FORCEPROP 2 LAST PATH I182
J 0
(-8475 4700);
DISPLAY 0.808511 (-8475 4700);
DISPLAY INVISIBLE (-8475 4700);
FORCEPROP 1 LAST COMMENT_BODY TRUE
J 0
(-8400 4525);
DISPLAY 0.872340 (-8400 4525);
PAINT GREEN (-8400 4525);
DISPLAY INVISIBLE (-8400 4525);
FORCEPROP 1 LAST OFFPAGE TRUE
J 0
(-8200 4500);
DISPLAY 0.872340 (-8200 4500);
PAINT GREEN (-8200 4500);
DISPLAY INVISIBLE (-8200 4500);
FORCEPROP 2 LAST CDS_LIB mstr_standard
J 0
(-8525 4625);
DISPLAY 0.723404 (-8525 4625);
PAINT MONO (-8525 4625);
DISPLAY INVISIBLE (-8525 4625);
FORCEADD OFFPAGE..1
(-8525 4725);
FORCEPROP 2 LAST $XR0 12 
J 0
(-8746 4725);
DISPLAY 0.638298 (-8746 4725);
PAINT MONO (-8746 4725);
FORCEPROP 2 LAST PATH I183
J 0
(-8475 4800);
DISPLAY 0.808511 (-8475 4800);
DISPLAY INVISIBLE (-8475 4800);
FORCEPROP 1 LAST COMMENT_BODY TRUE
J 0
(-8400 4625);
DISPLAY 0.872340 (-8400 4625);
PAINT GREEN (-8400 4625);
DISPLAY INVISIBLE (-8400 4625);
FORCEPROP 1 LAST OFFPAGE TRUE
J 0
(-8200 4600);
DISPLAY 0.872340 (-8200 4600);
PAINT GREEN (-8200 4600);
DISPLAY INVISIBLE (-8200 4600);
FORCEPROP 2 LAST CDS_LIB mstr_standard
J 0
(-8525 4725);
DISPLAY 0.808511 (-8525 4725);
DISPLAY INVISIBLE (-8525 4725);
FORCEADD OFFPAGE..1
(-8525 4775);
FORCEPROP 2 LAST $XR0 12 
J 0
(-8746 4775);
DISPLAY 0.638298 (-8746 4775);
PAINT MONO (-8746 4775);
FORCEPROP 2 LAST PATH I184
J 0
(-8475 4850);
DISPLAY 0.808511 (-8475 4850);
DISPLAY INVISIBLE (-8475 4850);
FORCEPROP 1 LAST COMMENT_BODY TRUE
J 0
(-8400 4675);
DISPLAY 0.872340 (-8400 4675);
PAINT GREEN (-8400 4675);
DISPLAY INVISIBLE (-8400 4675);
FORCEPROP 1 LAST OFFPAGE TRUE
J 0
(-8200 4650);
DISPLAY 0.872340 (-8200 4650);
PAINT GREEN (-8200 4650);
DISPLAY INVISIBLE (-8200 4650);
FORCEPROP 2 LAST CDS_LIB mstr_standard
J 0
(-8525 4775);
DISPLAY 0.723404 (-8525 4775);
PAINT MONO (-8525 4775);
DISPLAY INVISIBLE (-8525 4775);
FORCEADD OFFPAGE..1
(-8525 4925);
FORCEPROP 2 LAST $XR0 12 
J 0
(-8746 4925);
DISPLAY 0.638298 (-8746 4925);
PAINT MONO (-8746 4925);
FORCEPROP 2 LAST PATH I185
J 0
(-8475 5000);
DISPLAY 0.808511 (-8475 5000);
DISPLAY INVISIBLE (-8475 5000);
FORCEPROP 1 LAST COMMENT_BODY TRUE
J 0
(-8400 4825);
DISPLAY 0.872340 (-8400 4825);
PAINT GREEN (-8400 4825);
DISPLAY INVISIBLE (-8400 4825);
FORCEPROP 1 LAST OFFPAGE TRUE
J 0
(-8200 4800);
DISPLAY 0.872340 (-8200 4800);
PAINT GREEN (-8200 4800);
DISPLAY INVISIBLE (-8200 4800);
FORCEPROP 2 LAST CDS_LIB mstr_standard
J 0
(-8525 4925);
DISPLAY 0.723404 (-8525 4925);
PAINT MONO (-8525 4925);
DISPLAY INVISIBLE (-8525 4925);
FORCEADD OFFPAGE..1
(-8525 4875);
FORCEPROP 2 LAST $XR0 12 
J 0
(-8746 4875);
DISPLAY 0.638298 (-8746 4875);
PAINT MONO (-8746 4875);
FORCEPROP 2 LAST PATH I186
J 0
(-8475 4950);
DISPLAY 0.808511 (-8475 4950);
DISPLAY INVISIBLE (-8475 4950);
FORCEPROP 1 LAST COMMENT_BODY TRUE
J 0
(-8400 4775);
DISPLAY 0.872340 (-8400 4775);
PAINT GREEN (-8400 4775);
DISPLAY INVISIBLE (-8400 4775);
FORCEPROP 1 LAST OFFPAGE TRUE
J 0
(-8200 4750);
DISPLAY 0.872340 (-8200 4750);
PAINT GREEN (-8200 4750);
DISPLAY INVISIBLE (-8200 4750);
FORCEPROP 2 LAST CDS_LIB mstr_standard
J 0
(-8525 4875);
DISPLAY 0.808511 (-8525 4875);
DISPLAY INVISIBLE (-8525 4875);
FORCEADD TAP..1
R 2
(-7925 3575);
FORCEPROP 3 LASTPIN (-7875 3575) SIG_NAME M_C_CPU0_SB_CB<1>
J 0
(-7865 3585);
DISPLAY 0.659574 (-7865 3585);
PAINT MONO (-7865 3585);
DISPLAY INVISIBLE (-7865 3585);
FORCEPROP 1 LASTPIN (-7875 3575) BN 1
J 2
(-7863 3583);
DISPLAY 0.489362 (-7863 3583);
PAINT GREEN (-7863 3583);
FORCEPROP 2 LAST CDS_LIB mstr_standard
J 0
(-7925 3575);
DISPLAY 0.723404 (-7925 3575);
PAINT MONO (-7925 3575);
DISPLAY INVISIBLE (-7925 3575);
FORCEPROP 1 LAST BODY_TYPE PLUMBING
J 2
(-7925 3625);
DISPLAY 0.872340 (-7925 3625);
PAINT GREEN (-7925 3625);
DISPLAY INVISIBLE (-7925 3625);
FORCEPROP 1 LAST HDL_TAP TRUE
J 2
(-8250 3450);
DISPLAY 0.872340 (-8250 3450);
DISPLAY INVISIBLE (-8250 3450);
FORCEPROP 1 LAST PATH I187
J 2
(-7923 3575);
DISPLAY 0.872340 (-7923 3575);
PAINT GREEN (-7923 3575);
DISPLAY INVISIBLE (-7923 3575);
FORCEADD TAP..1
R 2
(-7925 3625);
FORCEPROP 3 LASTPIN (-7875 3625) SIG_NAME M_C_CPU0_SB_CB<2>
J 0
(-7865 3635);
DISPLAY 0.659574 (-7865 3635);
PAINT MONO (-7865 3635);
DISPLAY INVISIBLE (-7865 3635);
FORCEPROP 1 LASTPIN (-7875 3625) BN 2
J 2
(-7863 3633);
DISPLAY 0.489362 (-7863 3633);
PAINT GREEN (-7863 3633);
FORCEPROP 2 LAST CDS_LIB mstr_standard
J 0
(-7925 3625);
DISPLAY 0.723404 (-7925 3625);
PAINT MONO (-7925 3625);
DISPLAY INVISIBLE (-7925 3625);
FORCEPROP 1 LAST BODY_TYPE PLUMBING
J 2
(-7925 3675);
DISPLAY 0.872340 (-7925 3675);
PAINT GREEN (-7925 3675);
DISPLAY INVISIBLE (-7925 3675);
FORCEPROP 1 LAST HDL_TAP TRUE
J 2
(-8250 3500);
DISPLAY 0.872340 (-8250 3500);
DISPLAY INVISIBLE (-8250 3500);
FORCEPROP 1 LAST PATH I188
J 2
(-7923 3625);
DISPLAY 0.872340 (-7923 3625);
PAINT GREEN (-7923 3625);
DISPLAY INVISIBLE (-7923 3625);
FORCEADD TAP..1
R 2
(-7925 3525);
FORCEPROP 3 LASTPIN (-7875 3525) SIG_NAME M_C_CPU0_SB_CB<0>
J 0
(-7865 3535);
DISPLAY 0.659574 (-7865 3535);
PAINT MONO (-7865 3535);
DISPLAY INVISIBLE (-7865 3535);
FORCEPROP 1 LASTPIN (-7875 3525) BN 0
J 2
(-7863 3533);
DISPLAY 0.489362 (-7863 3533);
PAINT GREEN (-7863 3533);
FORCEPROP 2 LAST CDS_LIB mstr_standard
J 0
(-7925 3525);
DISPLAY 0.723404 (-7925 3525);
PAINT MONO (-7925 3525);
DISPLAY INVISIBLE (-7925 3525);
FORCEPROP 1 LAST BODY_TYPE PLUMBING
J 2
(-7925 3575);
DISPLAY 0.872340 (-7925 3575);
PAINT GREEN (-7925 3575);
DISPLAY INVISIBLE (-7925 3575);
FORCEPROP 1 LAST HDL_TAP TRUE
J 2
(-8250 3400);
DISPLAY 0.872340 (-8250 3400);
DISPLAY INVISIBLE (-8250 3400);
FORCEPROP 1 LAST PATH I189
J 2
(-7923 3525);
DISPLAY 0.872340 (-7923 3525);
PAINT GREEN (-7923 3525);
DISPLAY INVISIBLE (-7923 3525);
FORCEADD TAP..1
R 2
(-7925 3675);
FORCEPROP 3 LASTPIN (-7875 3675) SIG_NAME M_C_CPU0_SB_CB<3>
J 0
(-7865 3685);
DISPLAY 0.659574 (-7865 3685);
PAINT MONO (-7865 3685);
DISPLAY INVISIBLE (-7865 3685);
FORCEPROP 1 LASTPIN (-7875 3675) BN 3
J 2
(-7863 3683);
DISPLAY 0.489362 (-7863 3683);
PAINT GREEN (-7863 3683);
FORCEPROP 2 LAST CDS_LIB mstr_standard
J 0
(-7925 3675);
DISPLAY 0.723404 (-7925 3675);
PAINT MONO (-7925 3675);
DISPLAY INVISIBLE (-7925 3675);
FORCEPROP 1 LAST BODY_TYPE PLUMBING
J 2
(-7925 3725);
DISPLAY 0.872340 (-7925 3725);
PAINT GREEN (-7925 3725);
DISPLAY INVISIBLE (-7925 3725);
FORCEPROP 1 LAST HDL_TAP TRUE
J 2
(-8250 3550);
DISPLAY 0.872340 (-8250 3550);
DISPLAY INVISIBLE (-8250 3550);
FORCEPROP 1 LAST PATH I190
J 2
(-7923 3675);
DISPLAY 0.872340 (-7923 3675);
PAINT GREEN (-7923 3675);
DISPLAY INVISIBLE (-7923 3675);
FORCEADD TAP..1
R 2
(-7925 3725);
FORCEPROP 3 LASTPIN (-7875 3725) SIG_NAME M_C_CPU0_SB_CB<4>
J 0
(-7865 3735);
DISPLAY 0.659574 (-7865 3735);
PAINT MONO (-7865 3735);
DISPLAY INVISIBLE (-7865 3735);
FORCEPROP 1 LASTPIN (-7875 3725) BN 4
J 2
(-7863 3733);
DISPLAY 0.489362 (-7863 3733);
PAINT GREEN (-7863 3733);
FORCEPROP 2 LAST CDS_LIB mstr_standard
J 0
(-7925 3725);
DISPLAY 0.723404 (-7925 3725);
PAINT MONO (-7925 3725);
DISPLAY INVISIBLE (-7925 3725);
FORCEPROP 1 LAST BODY_TYPE PLUMBING
J 2
(-7925 3775);
DISPLAY 0.872340 (-7925 3775);
PAINT GREEN (-7925 3775);
DISPLAY INVISIBLE (-7925 3775);
FORCEPROP 1 LAST HDL_TAP TRUE
J 2
(-8250 3600);
DISPLAY 0.872340 (-8250 3600);
DISPLAY INVISIBLE (-8250 3600);
FORCEPROP 1 LAST PATH I191
J 2
(-7923 3725);
DISPLAY 0.872340 (-7923 3725);
PAINT GREEN (-7923 3725);
DISPLAY INVISIBLE (-7923 3725);
FORCEADD TAP..1
R 2
(-7925 3775);
FORCEPROP 3 LASTPIN (-7875 3775) SIG_NAME M_C_CPU0_SB_CB<5>
J 0
(-7865 3785);
DISPLAY 0.659574 (-7865 3785);
PAINT MONO (-7865 3785);
DISPLAY INVISIBLE (-7865 3785);
FORCEPROP 1 LASTPIN (-7875 3775) BN 5
J 2
(-7863 3783);
DISPLAY 0.489362 (-7863 3783);
PAINT GREEN (-7863 3783);
FORCEPROP 2 LAST CDS_LIB mstr_standard
J 0
(-7925 3775);
DISPLAY 0.723404 (-7925 3775);
PAINT MONO (-7925 3775);
DISPLAY INVISIBLE (-7925 3775);
FORCEPROP 1 LAST BODY_TYPE PLUMBING
J 2
(-7925 3825);
DISPLAY 0.872340 (-7925 3825);
PAINT GREEN (-7925 3825);
DISPLAY INVISIBLE (-7925 3825);
FORCEPROP 1 LAST HDL_TAP TRUE
J 2
(-8250 3650);
DISPLAY 0.872340 (-8250 3650);
DISPLAY INVISIBLE (-8250 3650);
FORCEPROP 1 LAST PATH I192
J 2
(-7923 3775);
DISPLAY 0.872340 (-7923 3775);
PAINT GREEN (-7923 3775);
DISPLAY INVISIBLE (-7923 3775);
FORCEADD TAP..1
R 2
(-7925 3875);
FORCEPROP 3 LASTPIN (-7875 3875) SIG_NAME M_C_CPU0_SB_CB<7>
J 0
(-7865 3885);
DISPLAY 0.659574 (-7865 3885);
PAINT MONO (-7865 3885);
DISPLAY INVISIBLE (-7865 3885);
FORCEPROP 1 LASTPIN (-7875 3875) BN 7
J 2
(-7863 3883);
DISPLAY 0.489362 (-7863 3883);
PAINT GREEN (-7863 3883);
FORCEPROP 2 LAST CDS_LIB mstr_standard
J 0
(-7925 3875);
DISPLAY 0.723404 (-7925 3875);
PAINT MONO (-7925 3875);
DISPLAY INVISIBLE (-7925 3875);
FORCEPROP 1 LAST BODY_TYPE PLUMBING
J 2
(-7925 3925);
DISPLAY 0.872340 (-7925 3925);
PAINT GREEN (-7925 3925);
DISPLAY INVISIBLE (-7925 3925);
FORCEPROP 1 LAST HDL_TAP TRUE
J 2
(-8250 3750);
DISPLAY 0.872340 (-8250 3750);
DISPLAY INVISIBLE (-8250 3750);
FORCEPROP 1 LAST PATH I193
J 2
(-7923 3875);
DISPLAY 0.872340 (-7923 3875);
PAINT GREEN (-7923 3875);
DISPLAY INVISIBLE (-7923 3875);
FORCEADD TAP..1
R 2
(-7925 3825);
FORCEPROP 3 LASTPIN (-7875 3825) SIG_NAME M_C_CPU0_SB_CB<6>
J 0
(-7865 3835);
DISPLAY 0.659574 (-7865 3835);
PAINT MONO (-7865 3835);
DISPLAY INVISIBLE (-7865 3835);
FORCEPROP 1 LASTPIN (-7875 3825) BN 6
J 2
(-7863 3833);
DISPLAY 0.489362 (-7863 3833);
PAINT GREEN (-7863 3833);
FORCEPROP 2 LAST CDS_LIB mstr_standard
J 0
(-7925 3825);
DISPLAY 0.723404 (-7925 3825);
PAINT MONO (-7925 3825);
DISPLAY INVISIBLE (-7925 3825);
FORCEPROP 1 LAST BODY_TYPE PLUMBING
J 2
(-7925 3875);
DISPLAY 0.872340 (-7925 3875);
PAINT GREEN (-7925 3875);
DISPLAY INVISIBLE (-7925 3875);
FORCEPROP 1 LAST HDL_TAP TRUE
J 2
(-8250 3700);
DISPLAY 0.872340 (-8250 3700);
DISPLAY INVISIBLE (-8250 3700);
FORCEPROP 1 LAST PATH I194
J 2
(-7923 3825);
DISPLAY 0.872340 (-7923 3825);
PAINT GREEN (-7923 3825);
DISPLAY INVISIBLE (-7923 3825);
FORCEADD TAP..1
R 2
(-7925 4075);
FORCEPROP 3 LASTPIN (-7875 4075) SIG_NAME M_C_CPU0_SA_CB<2>
J 0
(-7865 4085);
DISPLAY 0.659574 (-7865 4085);
PAINT MONO (-7865 4085);
DISPLAY INVISIBLE (-7865 4085);
FORCEPROP 1 LASTPIN (-7875 4075) BN 2
J 2
(-7863 4083);
DISPLAY 0.489362 (-7863 4083);
PAINT GREEN (-7863 4083);
FORCEPROP 2 LAST CDS_LIB mstr_standard
J 0
(-7925 4075);
DISPLAY 0.723404 (-7925 4075);
PAINT MONO (-7925 4075);
DISPLAY INVISIBLE (-7925 4075);
FORCEPROP 1 LAST BODY_TYPE PLUMBING
J 2
(-7925 4125);
DISPLAY 0.872340 (-7925 4125);
PAINT GREEN (-7925 4125);
DISPLAY INVISIBLE (-7925 4125);
FORCEPROP 1 LAST HDL_TAP TRUE
J 2
(-8250 3950);
DISPLAY 0.872340 (-8250 3950);
DISPLAY INVISIBLE (-8250 3950);
FORCEPROP 1 LAST PATH I195
J 2
(-7923 4075);
DISPLAY 0.872340 (-7923 4075);
PAINT GREEN (-7923 4075);
DISPLAY INVISIBLE (-7923 4075);
FORCEADD TAP..1
R 2
(-7925 4025);
FORCEPROP 3 LASTPIN (-7875 4025) SIG_NAME M_C_CPU0_SA_CB<1>
J 0
(-7865 4035);
DISPLAY 0.659574 (-7865 4035);
PAINT MONO (-7865 4035);
DISPLAY INVISIBLE (-7865 4035);
FORCEPROP 1 LASTPIN (-7875 4025) BN 1
J 2
(-7863 4033);
DISPLAY 0.489362 (-7863 4033);
PAINT GREEN (-7863 4033);
FORCEPROP 2 LAST CDS_LIB mstr_standard
J 0
(-7925 4025);
DISPLAY 0.723404 (-7925 4025);
PAINT MONO (-7925 4025);
DISPLAY INVISIBLE (-7925 4025);
FORCEPROP 1 LAST BODY_TYPE PLUMBING
J 2
(-7925 4075);
DISPLAY 0.872340 (-7925 4075);
PAINT GREEN (-7925 4075);
DISPLAY INVISIBLE (-7925 4075);
FORCEPROP 1 LAST HDL_TAP TRUE
J 2
(-8250 3900);
DISPLAY 0.872340 (-8250 3900);
DISPLAY INVISIBLE (-8250 3900);
FORCEPROP 1 LAST PATH I196
J 2
(-7923 4025);
DISPLAY 0.872340 (-7923 4025);
PAINT GREEN (-7923 4025);
DISPLAY INVISIBLE (-7923 4025);
FORCEADD TAP..1
R 2
(-7925 3975);
FORCEPROP 3 LASTPIN (-7875 3975) SIG_NAME M_C_CPU0_SA_CB<0>
J 0
(-7865 3985);
DISPLAY 0.659574 (-7865 3985);
PAINT MONO (-7865 3985);
DISPLAY INVISIBLE (-7865 3985);
FORCEPROP 1 LASTPIN (-7875 3975) BN 0
J 2
(-7863 3983);
DISPLAY 0.489362 (-7863 3983);
PAINT GREEN (-7863 3983);
FORCEPROP 2 LAST CDS_LIB mstr_standard
J 0
(-7925 3975);
DISPLAY 0.723404 (-7925 3975);
PAINT MONO (-7925 3975);
DISPLAY INVISIBLE (-7925 3975);
FORCEPROP 1 LAST BODY_TYPE PLUMBING
J 2
(-7925 4025);
DISPLAY 0.872340 (-7925 4025);
PAINT GREEN (-7925 4025);
DISPLAY INVISIBLE (-7925 4025);
FORCEPROP 1 LAST HDL_TAP TRUE
J 2
(-8250 3850);
DISPLAY 0.872340 (-8250 3850);
DISPLAY INVISIBLE (-8250 3850);
FORCEPROP 1 LAST PATH I197
J 2
(-7923 3975);
DISPLAY 0.872340 (-7923 3975);
PAINT GREEN (-7923 3975);
DISPLAY INVISIBLE (-7923 3975);
FORCEADD TAP..1
R 2
(-7925 4125);
FORCEPROP 3 LASTPIN (-7875 4125) SIG_NAME M_C_CPU0_SA_CB<3>
J 0
(-7865 4135);
DISPLAY 0.659574 (-7865 4135);
PAINT MONO (-7865 4135);
DISPLAY INVISIBLE (-7865 4135);
FORCEPROP 1 LASTPIN (-7875 4125) BN 3
J 2
(-7863 4133);
DISPLAY 0.489362 (-7863 4133);
PAINT GREEN (-7863 4133);
FORCEPROP 2 LAST CDS_LIB mstr_standard
J 0
(-7925 4125);
DISPLAY 0.723404 (-7925 4125);
PAINT MONO (-7925 4125);
DISPLAY INVISIBLE (-7925 4125);
FORCEPROP 1 LAST BODY_TYPE PLUMBING
J 2
(-7925 4175);
DISPLAY 0.872340 (-7925 4175);
PAINT GREEN (-7925 4175);
DISPLAY INVISIBLE (-7925 4175);
FORCEPROP 1 LAST HDL_TAP TRUE
J 2
(-8250 4000);
DISPLAY 0.872340 (-8250 4000);
DISPLAY INVISIBLE (-8250 4000);
FORCEPROP 1 LAST PATH I198
J 2
(-7923 4125);
DISPLAY 0.872340 (-7923 4125);
PAINT GREEN (-7923 4125);
DISPLAY INVISIBLE (-7923 4125);
FORCEADD TAP..1
R 2
(-7925 4175);
FORCEPROP 3 LASTPIN (-7875 4175) SIG_NAME M_C_CPU0_SA_CB<4>
J 0
(-7865 4185);
DISPLAY 0.659574 (-7865 4185);
PAINT MONO (-7865 4185);
DISPLAY INVISIBLE (-7865 4185);
FORCEPROP 1 LASTPIN (-7875 4175) BN 4
J 2
(-7863 4183);
DISPLAY 0.489362 (-7863 4183);
PAINT GREEN (-7863 4183);
FORCEPROP 2 LAST CDS_LIB mstr_standard
J 0
(-7925 4175);
DISPLAY 0.723404 (-7925 4175);
PAINT MONO (-7925 4175);
DISPLAY INVISIBLE (-7925 4175);
FORCEPROP 1 LAST BODY_TYPE PLUMBING
J 2
(-7925 4225);
DISPLAY 0.872340 (-7925 4225);
PAINT GREEN (-7925 4225);
DISPLAY INVISIBLE (-7925 4225);
FORCEPROP 1 LAST HDL_TAP TRUE
J 2
(-8250 4050);
DISPLAY 0.872340 (-8250 4050);
DISPLAY INVISIBLE (-8250 4050);
FORCEPROP 1 LAST PATH I199
J 2
(-7923 4175);
DISPLAY 0.872340 (-7923 4175);
PAINT GREEN (-7923 4175);
DISPLAY INVISIBLE (-7923 4175);
FORCEADD TAP..1
R 2
(-7925 4225);
FORCEPROP 3 LASTPIN (-7875 4225) SIG_NAME M_C_CPU0_SA_CB<5>
J 0
(-7865 4235);
DISPLAY 0.659574 (-7865 4235);
PAINT MONO (-7865 4235);
DISPLAY INVISIBLE (-7865 4235);
FORCEPROP 1 LASTPIN (-7875 4225) BN 5
J 2
(-7863 4233);
DISPLAY 0.489362 (-7863 4233);
PAINT GREEN (-7863 4233);
FORCEPROP 2 LAST CDS_LIB mstr_standard
J 0
(-7925 4225);
DISPLAY 0.723404 (-7925 4225);
PAINT MONO (-7925 4225);
DISPLAY INVISIBLE (-7925 4225);
FORCEPROP 1 LAST BODY_TYPE PLUMBING
J 2
(-7925 4275);
DISPLAY 0.872340 (-7925 4275);
PAINT GREEN (-7925 4275);
DISPLAY INVISIBLE (-7925 4275);
FORCEPROP 1 LAST HDL_TAP TRUE
J 2
(-8250 4100);
DISPLAY 0.872340 (-8250 4100);
DISPLAY INVISIBLE (-8250 4100);
FORCEPROP 1 LAST PATH I200
J 2
(-7923 4225);
DISPLAY 0.872340 (-7923 4225);
PAINT GREEN (-7923 4225);
DISPLAY INVISIBLE (-7923 4225);
FORCEADD TAP..1
R 2
(-7925 4275);
FORCEPROP 3 LASTPIN (-7875 4275) SIG_NAME M_C_CPU0_SA_CB<6>
J 0
(-7865 4285);
DISPLAY 0.659574 (-7865 4285);
PAINT MONO (-7865 4285);
DISPLAY INVISIBLE (-7865 4285);
FORCEPROP 1 LASTPIN (-7875 4275) BN 6
J 2
(-7863 4283);
DISPLAY 0.489362 (-7863 4283);
PAINT GREEN (-7863 4283);
FORCEPROP 2 LAST CDS_LIB mstr_standard
J 0
(-7925 4275);
DISPLAY 0.723404 (-7925 4275);
PAINT MONO (-7925 4275);
DISPLAY INVISIBLE (-7925 4275);
FORCEPROP 1 LAST BODY_TYPE PLUMBING
J 2
(-7925 4325);
DISPLAY 0.872340 (-7925 4325);
PAINT GREEN (-7925 4325);
DISPLAY INVISIBLE (-7925 4325);
FORCEPROP 1 LAST HDL_TAP TRUE
J 2
(-8250 4150);
DISPLAY 0.872340 (-8250 4150);
DISPLAY INVISIBLE (-8250 4150);
FORCEPROP 1 LAST PATH I201
J 2
(-7923 4275);
DISPLAY 0.872340 (-7923 4275);
PAINT GREEN (-7923 4275);
DISPLAY INVISIBLE (-7923 4275);
FORCEADD TAP..1
R 2
(-7925 4325);
FORCEPROP 3 LASTPIN (-7875 4325) SIG_NAME M_C_CPU0_SA_CB<7>
J 0
(-7865 4335);
DISPLAY 0.659574 (-7865 4335);
PAINT MONO (-7865 4335);
DISPLAY INVISIBLE (-7865 4335);
FORCEPROP 1 LASTPIN (-7875 4325) BN 7
J 2
(-7863 4333);
DISPLAY 0.489362 (-7863 4333);
PAINT GREEN (-7863 4333);
FORCEPROP 2 LAST CDS_LIB mstr_standard
J 0
(-7925 4325);
DISPLAY 0.723404 (-7925 4325);
PAINT MONO (-7925 4325);
DISPLAY INVISIBLE (-7925 4325);
FORCEPROP 1 LAST BODY_TYPE PLUMBING
J 2
(-7925 4375);
DISPLAY 0.872340 (-7925 4375);
PAINT GREEN (-7925 4375);
DISPLAY INVISIBLE (-7925 4375);
FORCEPROP 1 LAST HDL_TAP TRUE
J 2
(-8250 4200);
DISPLAY 0.872340 (-8250 4200);
DISPLAY INVISIBLE (-8250 4200);
FORCEPROP 1 LAST PATH I202
J 2
(-7923 4325);
DISPLAY 0.872340 (-7923 4325);
PAINT GREEN (-7923 4325);
DISPLAY INVISIBLE (-7923 4325);
FORCEADD TAP..1
R 2
(-7925 5175);
FORCEPROP 3 LASTPIN (-7875 5175) SIG_NAME M_C_CPU0_SB_CA<3>
J 0
(-7865 5185);
DISPLAY 0.659574 (-7865 5185);
PAINT MONO (-7865 5185);
DISPLAY INVISIBLE (-7865 5185);
FORCEPROP 1 LASTPIN (-7875 5175) BN 3
J 2
(-7863 5183);
DISPLAY 0.489362 (-7863 5183);
PAINT GREEN (-7863 5183);
FORCEPROP 2 LAST CDS_LIB mstr_standard
J 0
(-7925 5175);
DISPLAY 0.723404 (-7925 5175);
PAINT MONO (-7925 5175);
DISPLAY INVISIBLE (-7925 5175);
FORCEPROP 1 LAST BODY_TYPE PLUMBING
J 2
(-7925 5225);
DISPLAY 0.872340 (-7925 5225);
PAINT GREEN (-7925 5225);
DISPLAY INVISIBLE (-7925 5225);
FORCEPROP 1 LAST HDL_TAP TRUE
J 2
(-8250 5050);
DISPLAY 0.872340 (-8250 5050);
DISPLAY INVISIBLE (-8250 5050);
FORCEPROP 1 LAST PATH I203
J 2
(-7923 5175);
DISPLAY 0.872340 (-7923 5175);
PAINT GREEN (-7923 5175);
DISPLAY INVISIBLE (-7923 5175);
FORCEADD TAP..1
R 2
(-7925 5075);
FORCEPROP 3 LASTPIN (-7875 5075) SIG_NAME M_C_CPU0_SB_CA<1>
J 0
(-7865 5085);
DISPLAY 0.659574 (-7865 5085);
PAINT MONO (-7865 5085);
DISPLAY INVISIBLE (-7865 5085);
FORCEPROP 1 LASTPIN (-7875 5075) BN 1
J 2
(-7863 5083);
DISPLAY 0.489362 (-7863 5083);
PAINT GREEN (-7863 5083);
FORCEPROP 2 LAST CDS_LIB mstr_standard
J 0
(-7925 5075);
DISPLAY 0.723404 (-7925 5075);
PAINT MONO (-7925 5075);
DISPLAY INVISIBLE (-7925 5075);
FORCEPROP 1 LAST BODY_TYPE PLUMBING
J 2
(-7925 5125);
DISPLAY 0.872340 (-7925 5125);
PAINT GREEN (-7925 5125);
DISPLAY INVISIBLE (-7925 5125);
FORCEPROP 1 LAST HDL_TAP TRUE
J 2
(-8250 4950);
DISPLAY 0.872340 (-8250 4950);
DISPLAY INVISIBLE (-8250 4950);
FORCEPROP 1 LAST PATH I204
J 2
(-7923 5075);
DISPLAY 0.872340 (-7923 5075);
PAINT GREEN (-7923 5075);
DISPLAY INVISIBLE (-7923 5075);
FORCEADD TAP..1
R 2
(-7925 5025);
FORCEPROP 3 LASTPIN (-7875 5025) SIG_NAME M_C_CPU0_SB_CA<0>
J 0
(-7865 5035);
DISPLAY 0.659574 (-7865 5035);
PAINT MONO (-7865 5035);
DISPLAY INVISIBLE (-7865 5035);
FORCEPROP 1 LASTPIN (-7875 5025) BN 0
J 2
(-7863 5033);
DISPLAY 0.489362 (-7863 5033);
PAINT GREEN (-7863 5033);
FORCEPROP 2 LAST CDS_LIB mstr_standard
J 0
(-7925 5025);
DISPLAY 0.723404 (-7925 5025);
PAINT MONO (-7925 5025);
DISPLAY INVISIBLE (-7925 5025);
FORCEPROP 1 LAST BODY_TYPE PLUMBING
J 2
(-7925 5075);
DISPLAY 0.872340 (-7925 5075);
PAINT GREEN (-7925 5075);
DISPLAY INVISIBLE (-7925 5075);
FORCEPROP 1 LAST HDL_TAP TRUE
J 2
(-8250 4900);
DISPLAY 0.872340 (-8250 4900);
DISPLAY INVISIBLE (-8250 4900);
FORCEPROP 1 LAST PATH I205
J 2
(-7923 5025);
DISPLAY 0.872340 (-7923 5025);
PAINT GREEN (-7923 5025);
DISPLAY INVISIBLE (-7923 5025);
FORCEADD TAP..1
R 2
(-7925 5125);
FORCEPROP 3 LASTPIN (-7875 5125) SIG_NAME M_C_CPU0_SB_CA<2>
J 0
(-7865 5135);
DISPLAY 0.659574 (-7865 5135);
PAINT MONO (-7865 5135);
DISPLAY INVISIBLE (-7865 5135);
FORCEPROP 1 LASTPIN (-7875 5125) BN 2
J 2
(-7863 5133);
DISPLAY 0.489362 (-7863 5133);
PAINT GREEN (-7863 5133);
FORCEPROP 2 LAST CDS_LIB mstr_standard
J 0
(-7925 5125);
DISPLAY 0.723404 (-7925 5125);
PAINT MONO (-7925 5125);
DISPLAY INVISIBLE (-7925 5125);
FORCEPROP 1 LAST BODY_TYPE PLUMBING
J 2
(-7925 5175);
DISPLAY 0.872340 (-7925 5175);
PAINT GREEN (-7925 5175);
DISPLAY INVISIBLE (-7925 5175);
FORCEPROP 1 LAST HDL_TAP TRUE
J 2
(-8250 5000);
DISPLAY 0.872340 (-8250 5000);
DISPLAY INVISIBLE (-8250 5000);
FORCEPROP 1 LAST PATH I206
J 2
(-7923 5125);
DISPLAY 0.872340 (-7923 5125);
PAINT GREEN (-7923 5125);
DISPLAY INVISIBLE (-7923 5125);
FORCEADD TAP..1
(-6225 2575);
FORCEPROP 3 LASTPIN (-6275 2575) SIG_NAME M_C_CPU0_SB_DQ<1>
J 0
(-6265 2585);
DISPLAY 0.659574 (-6265 2585);
PAINT MONO (-6265 2585);
DISPLAY INVISIBLE (-6265 2585);
FORCEPROP 1 LASTPIN (-6275 2575) BN 1
J 0
(-6287 2583);
DISPLAY 0.489362 (-6287 2583);
PAINT GREEN (-6287 2583);
FORCEPROP 2 LAST CDS_LIB mstr_standard
J 0
(-6225 2575);
DISPLAY 0.723404 (-6225 2575);
PAINT MONO (-6225 2575);
DISPLAY INVISIBLE (-6225 2575);
FORCEPROP 1 LAST BODY_TYPE PLUMBING
J 0
(-6225 2625);
DISPLAY 0.872340 (-6225 2625);
PAINT GREEN (-6225 2625);
DISPLAY INVISIBLE (-6225 2625);
FORCEPROP 1 LAST HDL_TAP TRUE
J 0
(-5900 2450);
DISPLAY 0.872340 (-5900 2450);
DISPLAY INVISIBLE (-5900 2450);
FORCEPROP 1 LAST PATH I207
J 0
(-6227 2575);
DISPLAY 0.872340 (-6227 2575);
PAINT GREEN (-6227 2575);
DISPLAY INVISIBLE (-6227 2575);
FORCEADD TAP..1
(-6225 2525);
FORCEPROP 3 LASTPIN (-6275 2525) SIG_NAME M_C_CPU0_SB_DQ<0>
J 0
(-6265 2535);
DISPLAY 0.659574 (-6265 2535);
PAINT MONO (-6265 2535);
DISPLAY INVISIBLE (-6265 2535);
FORCEPROP 1 LASTPIN (-6275 2525) BN 0
J 0
(-6287 2533);
DISPLAY 0.489362 (-6287 2533);
PAINT GREEN (-6287 2533);
FORCEPROP 2 LAST CDS_LIB mstr_standard
J 0
(-6225 2525);
DISPLAY 0.723404 (-6225 2525);
PAINT MONO (-6225 2525);
DISPLAY INVISIBLE (-6225 2525);
FORCEPROP 1 LAST BODY_TYPE PLUMBING
J 0
(-6225 2575);
DISPLAY 0.872340 (-6225 2575);
PAINT GREEN (-6225 2575);
DISPLAY INVISIBLE (-6225 2575);
FORCEPROP 1 LAST HDL_TAP TRUE
J 0
(-5900 2400);
DISPLAY 0.872340 (-5900 2400);
DISPLAY INVISIBLE (-5900 2400);
FORCEPROP 1 LAST PATH I208
J 0
(-6227 2525);
DISPLAY 0.872340 (-6227 2525);
PAINT GREEN (-6227 2525);
DISPLAY INVISIBLE (-6227 2525);
FORCEADD TAP..1
(-6225 2625);
FORCEPROP 3 LASTPIN (-6275 2625) SIG_NAME M_C_CPU0_SB_DQ<2>
J 0
(-6265 2635);
DISPLAY 0.659574 (-6265 2635);
PAINT MONO (-6265 2635);
DISPLAY INVISIBLE (-6265 2635);
FORCEPROP 1 LASTPIN (-6275 2625) BN 2
J 0
(-6287 2633);
DISPLAY 0.489362 (-6287 2633);
PAINT GREEN (-6287 2633);
FORCEPROP 2 LAST CDS_LIB mstr_standard
J 0
(-6225 2625);
DISPLAY 0.723404 (-6225 2625);
PAINT MONO (-6225 2625);
DISPLAY INVISIBLE (-6225 2625);
FORCEPROP 1 LAST BODY_TYPE PLUMBING
J 0
(-6225 2675);
DISPLAY 0.872340 (-6225 2675);
PAINT GREEN (-6225 2675);
DISPLAY INVISIBLE (-6225 2675);
FORCEPROP 1 LAST HDL_TAP TRUE
J 0
(-5900 2500);
DISPLAY 0.872340 (-5900 2500);
DISPLAY INVISIBLE (-5900 2500);
FORCEPROP 1 LAST PATH I209
J 0
(-6227 2625);
DISPLAY 0.872340 (-6227 2625);
PAINT GREEN (-6227 2625);
DISPLAY INVISIBLE (-6227 2625);
FORCEADD TAP..1
(-6225 2675);
FORCEPROP 3 LASTPIN (-6275 2675) SIG_NAME M_C_CPU0_SB_DQ<3>
J 0
(-6265 2685);
DISPLAY 0.659574 (-6265 2685);
PAINT MONO (-6265 2685);
DISPLAY INVISIBLE (-6265 2685);
FORCEPROP 1 LASTPIN (-6275 2675) BN 3
J 0
(-6287 2683);
DISPLAY 0.489362 (-6287 2683);
PAINT GREEN (-6287 2683);
FORCEPROP 2 LAST CDS_LIB mstr_standard
J 0
(-6225 2675);
DISPLAY 0.723404 (-6225 2675);
PAINT MONO (-6225 2675);
DISPLAY INVISIBLE (-6225 2675);
FORCEPROP 1 LAST BODY_TYPE PLUMBING
J 0
(-6225 2725);
DISPLAY 0.872340 (-6225 2725);
PAINT GREEN (-6225 2725);
DISPLAY INVISIBLE (-6225 2725);
FORCEPROP 1 LAST HDL_TAP TRUE
J 0
(-5900 2550);
DISPLAY 0.872340 (-5900 2550);
DISPLAY INVISIBLE (-5900 2550);
FORCEPROP 1 LAST PATH I210
J 0
(-6227 2675);
DISPLAY 0.872340 (-6227 2675);
PAINT GREEN (-6227 2675);
DISPLAY INVISIBLE (-6227 2675);
FORCEADD TAP..1
(-6225 2725);
FORCEPROP 3 LASTPIN (-6275 2725) SIG_NAME M_C_CPU0_SB_DQ<4>
J 0
(-6265 2735);
DISPLAY 0.659574 (-6265 2735);
PAINT MONO (-6265 2735);
DISPLAY INVISIBLE (-6265 2735);
FORCEPROP 1 LASTPIN (-6275 2725) BN 4
J 0
(-6287 2733);
DISPLAY 0.489362 (-6287 2733);
PAINT GREEN (-6287 2733);
FORCEPROP 2 LAST CDS_LIB mstr_standard
J 0
(-6225 2725);
DISPLAY 0.723404 (-6225 2725);
PAINT MONO (-6225 2725);
DISPLAY INVISIBLE (-6225 2725);
FORCEPROP 1 LAST BODY_TYPE PLUMBING
J 0
(-6225 2775);
DISPLAY 0.872340 (-6225 2775);
PAINT GREEN (-6225 2775);
DISPLAY INVISIBLE (-6225 2775);
FORCEPROP 1 LAST HDL_TAP TRUE
J 0
(-5900 2600);
DISPLAY 0.872340 (-5900 2600);
DISPLAY INVISIBLE (-5900 2600);
FORCEPROP 1 LAST PATH I211
J 0
(-6227 2725);
DISPLAY 0.872340 (-6227 2725);
PAINT GREEN (-6227 2725);
DISPLAY INVISIBLE (-6227 2725);
FORCEADD TAP..1
(-6225 2775);
FORCEPROP 3 LASTPIN (-6275 2775) SIG_NAME M_C_CPU0_SB_DQ<5>
J 0
(-6265 2785);
DISPLAY 0.659574 (-6265 2785);
PAINT MONO (-6265 2785);
DISPLAY INVISIBLE (-6265 2785);
FORCEPROP 1 LASTPIN (-6275 2775) BN 5
J 0
(-6287 2783);
DISPLAY 0.489362 (-6287 2783);
PAINT GREEN (-6287 2783);
FORCEPROP 2 LAST CDS_LIB mstr_standard
J 0
(-6225 2775);
DISPLAY 0.723404 (-6225 2775);
PAINT MONO (-6225 2775);
DISPLAY INVISIBLE (-6225 2775);
FORCEPROP 1 LAST BODY_TYPE PLUMBING
J 0
(-6225 2825);
DISPLAY 0.872340 (-6225 2825);
PAINT GREEN (-6225 2825);
DISPLAY INVISIBLE (-6225 2825);
FORCEPROP 1 LAST HDL_TAP TRUE
J 0
(-5900 2650);
DISPLAY 0.872340 (-5900 2650);
DISPLAY INVISIBLE (-5900 2650);
FORCEPROP 1 LAST PATH I212
J 0
(-6227 2775);
DISPLAY 0.872340 (-6227 2775);
PAINT GREEN (-6227 2775);
DISPLAY INVISIBLE (-6227 2775);
FORCEADD TAP..1
(-6225 2875);
FORCEPROP 3 LASTPIN (-6275 2875) SIG_NAME M_C_CPU0_SB_DQ<7>
J 0
(-6265 2885);
DISPLAY 0.659574 (-6265 2885);
PAINT MONO (-6265 2885);
DISPLAY INVISIBLE (-6265 2885);
FORCEPROP 1 LASTPIN (-6275 2875) BN 7
J 0
(-6287 2883);
DISPLAY 0.489362 (-6287 2883);
PAINT GREEN (-6287 2883);
FORCEPROP 2 LAST CDS_LIB mstr_standard
J 0
(-6225 2875);
DISPLAY 0.723404 (-6225 2875);
PAINT MONO (-6225 2875);
DISPLAY INVISIBLE (-6225 2875);
FORCEPROP 1 LAST BODY_TYPE PLUMBING
J 0
(-6225 2925);
DISPLAY 0.872340 (-6225 2925);
PAINT GREEN (-6225 2925);
DISPLAY INVISIBLE (-6225 2925);
FORCEPROP 1 LAST HDL_TAP TRUE
J 0
(-5900 2750);
DISPLAY 0.872340 (-5900 2750);
DISPLAY INVISIBLE (-5900 2750);
FORCEPROP 1 LAST PATH I213
J 0
(-6227 2875);
DISPLAY 0.872340 (-6227 2875);
PAINT GREEN (-6227 2875);
DISPLAY INVISIBLE (-6227 2875);
FORCEADD TAP..1
(-6225 2825);
FORCEPROP 3 LASTPIN (-6275 2825) SIG_NAME M_C_CPU0_SB_DQ<6>
J 0
(-6265 2835);
DISPLAY 0.659574 (-6265 2835);
PAINT MONO (-6265 2835);
DISPLAY INVISIBLE (-6265 2835);
FORCEPROP 1 LASTPIN (-6275 2825) BN 6
J 0
(-6287 2833);
DISPLAY 0.489362 (-6287 2833);
PAINT GREEN (-6287 2833);
FORCEPROP 2 LAST CDS_LIB mstr_standard
J 0
(-6225 2825);
DISPLAY 0.723404 (-6225 2825);
PAINT MONO (-6225 2825);
DISPLAY INVISIBLE (-6225 2825);
FORCEPROP 1 LAST BODY_TYPE PLUMBING
J 0
(-6225 2875);
DISPLAY 0.872340 (-6225 2875);
PAINT GREEN (-6225 2875);
DISPLAY INVISIBLE (-6225 2875);
FORCEPROP 1 LAST HDL_TAP TRUE
J 0
(-5900 2700);
DISPLAY 0.872340 (-5900 2700);
DISPLAY INVISIBLE (-5900 2700);
FORCEPROP 1 LAST PATH I214
J 0
(-6227 2825);
DISPLAY 0.872340 (-6227 2825);
PAINT GREEN (-6227 2825);
DISPLAY INVISIBLE (-6227 2825);
FORCEADD TAP..1
(-6225 2925);
FORCEPROP 3 LASTPIN (-6275 2925) SIG_NAME M_C_CPU0_SB_DQ<8>
J 0
(-6265 2935);
DISPLAY 0.659574 (-6265 2935);
PAINT MONO (-6265 2935);
DISPLAY INVISIBLE (-6265 2935);
FORCEPROP 1 LASTPIN (-6275 2925) BN 8
J 0
(-6287 2933);
DISPLAY 0.489362 (-6287 2933);
PAINT GREEN (-6287 2933);
FORCEPROP 2 LAST CDS_LIB mstr_standard
J 0
(-6225 2925);
DISPLAY 0.723404 (-6225 2925);
PAINT MONO (-6225 2925);
DISPLAY INVISIBLE (-6225 2925);
FORCEPROP 1 LAST BODY_TYPE PLUMBING
J 0
(-6225 2975);
DISPLAY 0.872340 (-6225 2975);
PAINT GREEN (-6225 2975);
DISPLAY INVISIBLE (-6225 2975);
FORCEPROP 1 LAST HDL_TAP TRUE
J 0
(-5900 2800);
DISPLAY 0.872340 (-5900 2800);
DISPLAY INVISIBLE (-5900 2800);
FORCEPROP 1 LAST PATH I215
J 0
(-6227 2925);
DISPLAY 0.872340 (-6227 2925);
PAINT GREEN (-6227 2925);
DISPLAY INVISIBLE (-6227 2925);
FORCEADD TAP..1
(-6225 2975);
FORCEPROP 3 LASTPIN (-6275 2975) SIG_NAME M_C_CPU0_SB_DQ<9>
J 0
(-6265 2985);
DISPLAY 0.659574 (-6265 2985);
PAINT MONO (-6265 2985);
DISPLAY INVISIBLE (-6265 2985);
FORCEPROP 1 LASTPIN (-6275 2975) BN 9
J 0
(-6287 2983);
DISPLAY 0.489362 (-6287 2983);
PAINT GREEN (-6287 2983);
FORCEPROP 2 LAST CDS_LIB mstr_standard
J 0
(-6225 2975);
DISPLAY 0.723404 (-6225 2975);
PAINT MONO (-6225 2975);
DISPLAY INVISIBLE (-6225 2975);
FORCEPROP 1 LAST BODY_TYPE PLUMBING
J 0
(-6225 3025);
DISPLAY 0.872340 (-6225 3025);
PAINT GREEN (-6225 3025);
DISPLAY INVISIBLE (-6225 3025);
FORCEPROP 1 LAST HDL_TAP TRUE
J 0
(-5900 2850);
DISPLAY 0.872340 (-5900 2850);
DISPLAY INVISIBLE (-5900 2850);
FORCEPROP 1 LAST PATH I216
J 0
(-6227 2975);
DISPLAY 0.872340 (-6227 2975);
PAINT GREEN (-6227 2975);
DISPLAY INVISIBLE (-6227 2975);
FORCEADD TAP..1
(-6225 3025);
FORCEPROP 3 LASTPIN (-6275 3025) SIG_NAME M_C_CPU0_SB_DQ<10>
J 0
(-6265 3035);
DISPLAY 0.659574 (-6265 3035);
PAINT MONO (-6265 3035);
DISPLAY INVISIBLE (-6265 3035);
FORCEPROP 1 LASTPIN (-6275 3025) BN 10
J 0
(-6287 3033);
DISPLAY 0.489362 (-6287 3033);
PAINT GREEN (-6287 3033);
FORCEPROP 2 LAST CDS_LIB mstr_standard
J 0
(-6225 3025);
DISPLAY 0.723404 (-6225 3025);
PAINT MONO (-6225 3025);
DISPLAY INVISIBLE (-6225 3025);
FORCEPROP 1 LAST BODY_TYPE PLUMBING
J 0
(-6225 3075);
DISPLAY 0.872340 (-6225 3075);
PAINT GREEN (-6225 3075);
DISPLAY INVISIBLE (-6225 3075);
FORCEPROP 1 LAST HDL_TAP TRUE
J 0
(-5900 2900);
DISPLAY 0.872340 (-5900 2900);
DISPLAY INVISIBLE (-5900 2900);
FORCEPROP 1 LAST PATH I217
J 0
(-6227 3025);
DISPLAY 0.872340 (-6227 3025);
PAINT GREEN (-6227 3025);
DISPLAY INVISIBLE (-6227 3025);
FORCEADD TAP..1
(-6225 3075);
FORCEPROP 3 LASTPIN (-6275 3075) SIG_NAME M_C_CPU0_SB_DQ<11>
J 0
(-6265 3085);
DISPLAY 0.659574 (-6265 3085);
PAINT MONO (-6265 3085);
DISPLAY INVISIBLE (-6265 3085);
FORCEPROP 1 LASTPIN (-6275 3075) BN 11
J 0
(-6287 3083);
DISPLAY 0.489362 (-6287 3083);
PAINT GREEN (-6287 3083);
FORCEPROP 2 LAST CDS_LIB mstr_standard
J 0
(-6225 3075);
DISPLAY 0.723404 (-6225 3075);
PAINT MONO (-6225 3075);
DISPLAY INVISIBLE (-6225 3075);
FORCEPROP 1 LAST BODY_TYPE PLUMBING
J 0
(-6225 3125);
DISPLAY 0.872340 (-6225 3125);
PAINT GREEN (-6225 3125);
DISPLAY INVISIBLE (-6225 3125);
FORCEPROP 1 LAST HDL_TAP TRUE
J 0
(-5900 2950);
DISPLAY 0.872340 (-5900 2950);
DISPLAY INVISIBLE (-5900 2950);
FORCEPROP 1 LAST PATH I218
J 0
(-6227 3075);
DISPLAY 0.872340 (-6227 3075);
PAINT GREEN (-6227 3075);
DISPLAY INVISIBLE (-6227 3075);
FORCEADD TAP..1
(-6225 3125);
FORCEPROP 3 LASTPIN (-6275 3125) SIG_NAME M_C_CPU0_SB_DQ<12>
J 0
(-6265 3135);
DISPLAY 0.659574 (-6265 3135);
PAINT MONO (-6265 3135);
DISPLAY INVISIBLE (-6265 3135);
FORCEPROP 1 LASTPIN (-6275 3125) BN 12
J 0
(-6287 3133);
DISPLAY 0.489362 (-6287 3133);
PAINT GREEN (-6287 3133);
FORCEPROP 2 LAST CDS_LIB mstr_standard
J 0
(-6225 3125);
DISPLAY 0.723404 (-6225 3125);
PAINT MONO (-6225 3125);
DISPLAY INVISIBLE (-6225 3125);
FORCEPROP 1 LAST BODY_TYPE PLUMBING
J 0
(-6225 3175);
DISPLAY 0.872340 (-6225 3175);
PAINT GREEN (-6225 3175);
DISPLAY INVISIBLE (-6225 3175);
FORCEPROP 1 LAST HDL_TAP TRUE
J 0
(-5900 3000);
DISPLAY 0.872340 (-5900 3000);
DISPLAY INVISIBLE (-5900 3000);
FORCEPROP 1 LAST PATH I219
J 0
(-6227 3125);
DISPLAY 0.872340 (-6227 3125);
PAINT GREEN (-6227 3125);
DISPLAY INVISIBLE (-6227 3125);
FORCEADD TAP..1
(-6225 3175);
FORCEPROP 3 LASTPIN (-6275 3175) SIG_NAME M_C_CPU0_SB_DQ<13>
J 0
(-6265 3185);
DISPLAY 0.659574 (-6265 3185);
PAINT MONO (-6265 3185);
DISPLAY INVISIBLE (-6265 3185);
FORCEPROP 1 LASTPIN (-6275 3175) BN 13
J 0
(-6287 3183);
DISPLAY 0.489362 (-6287 3183);
PAINT GREEN (-6287 3183);
FORCEPROP 2 LAST CDS_LIB mstr_standard
J 0
(-6225 3175);
DISPLAY 0.723404 (-6225 3175);
PAINT MONO (-6225 3175);
DISPLAY INVISIBLE (-6225 3175);
FORCEPROP 1 LAST BODY_TYPE PLUMBING
J 0
(-6225 3225);
DISPLAY 0.872340 (-6225 3225);
PAINT GREEN (-6225 3225);
DISPLAY INVISIBLE (-6225 3225);
FORCEPROP 1 LAST HDL_TAP TRUE
J 0
(-5900 3050);
DISPLAY 0.872340 (-5900 3050);
DISPLAY INVISIBLE (-5900 3050);
FORCEPROP 1 LAST PATH I220
J 0
(-6227 3175);
DISPLAY 0.872340 (-6227 3175);
PAINT GREEN (-6227 3175);
DISPLAY INVISIBLE (-6227 3175);
FORCEADD TAP..1
(-6225 3275);
FORCEPROP 3 LASTPIN (-6275 3275) SIG_NAME M_C_CPU0_SB_DQ<15>
J 0
(-6265 3285);
DISPLAY 0.659574 (-6265 3285);
PAINT MONO (-6265 3285);
DISPLAY INVISIBLE (-6265 3285);
FORCEPROP 1 LASTPIN (-6275 3275) BN 15
J 0
(-6287 3283);
DISPLAY 0.489362 (-6287 3283);
PAINT GREEN (-6287 3283);
FORCEPROP 2 LAST CDS_LIB mstr_standard
J 0
(-6225 3275);
DISPLAY 0.723404 (-6225 3275);
PAINT MONO (-6225 3275);
DISPLAY INVISIBLE (-6225 3275);
FORCEPROP 1 LAST BODY_TYPE PLUMBING
J 0
(-6225 3325);
DISPLAY 0.872340 (-6225 3325);
PAINT GREEN (-6225 3325);
DISPLAY INVISIBLE (-6225 3325);
FORCEPROP 1 LAST HDL_TAP TRUE
J 0
(-5900 3150);
DISPLAY 0.872340 (-5900 3150);
DISPLAY INVISIBLE (-5900 3150);
FORCEPROP 1 LAST PATH I221
J 0
(-6227 3275);
DISPLAY 0.872340 (-6227 3275);
PAINT GREEN (-6227 3275);
DISPLAY INVISIBLE (-6227 3275);
FORCEADD TAP..1
(-6225 3225);
FORCEPROP 3 LASTPIN (-6275 3225) SIG_NAME M_C_CPU0_SB_DQ<14>
J 0
(-6265 3235);
DISPLAY 0.659574 (-6265 3235);
PAINT MONO (-6265 3235);
DISPLAY INVISIBLE (-6265 3235);
FORCEPROP 1 LASTPIN (-6275 3225) BN 14
J 0
(-6287 3233);
DISPLAY 0.489362 (-6287 3233);
PAINT GREEN (-6287 3233);
FORCEPROP 2 LAST CDS_LIB mstr_standard
J 0
(-6225 3225);
DISPLAY 0.723404 (-6225 3225);
PAINT MONO (-6225 3225);
DISPLAY INVISIBLE (-6225 3225);
FORCEPROP 1 LAST BODY_TYPE PLUMBING
J 0
(-6225 3275);
DISPLAY 0.872340 (-6225 3275);
PAINT GREEN (-6225 3275);
DISPLAY INVISIBLE (-6225 3275);
FORCEPROP 1 LAST HDL_TAP TRUE
J 0
(-5900 3100);
DISPLAY 0.872340 (-5900 3100);
DISPLAY INVISIBLE (-5900 3100);
FORCEPROP 1 LAST PATH I222
J 0
(-6227 3225);
DISPLAY 0.872340 (-6227 3225);
PAINT GREEN (-6227 3225);
DISPLAY INVISIBLE (-6227 3225);
FORCEADD TAP..1
(-6225 3425);
FORCEPROP 3 LASTPIN (-6275 3425) SIG_NAME M_C_CPU0_SB_DQ<18>
J 0
(-6265 3435);
DISPLAY 0.659574 (-6265 3435);
PAINT MONO (-6265 3435);
DISPLAY INVISIBLE (-6265 3435);
FORCEPROP 1 LASTPIN (-6275 3425) BN 18
J 0
(-6287 3433);
DISPLAY 0.489362 (-6287 3433);
PAINT GREEN (-6287 3433);
FORCEPROP 2 LAST CDS_LIB mstr_standard
J 0
(-6225 3425);
DISPLAY 0.723404 (-6225 3425);
PAINT MONO (-6225 3425);
DISPLAY INVISIBLE (-6225 3425);
FORCEPROP 1 LAST BODY_TYPE PLUMBING
J 0
(-6225 3475);
DISPLAY 0.872340 (-6225 3475);
PAINT GREEN (-6225 3475);
DISPLAY INVISIBLE (-6225 3475);
FORCEPROP 1 LAST HDL_TAP TRUE
J 0
(-5900 3300);
DISPLAY 0.872340 (-5900 3300);
DISPLAY INVISIBLE (-5900 3300);
FORCEPROP 1 LAST PATH I223
J 0
(-6227 3425);
DISPLAY 0.872340 (-6227 3425);
PAINT GREEN (-6227 3425);
DISPLAY INVISIBLE (-6227 3425);
FORCEADD TAP..1
(-6225 3375);
FORCEPROP 3 LASTPIN (-6275 3375) SIG_NAME M_C_CPU0_SB_DQ<17>
J 0
(-6265 3385);
DISPLAY 0.659574 (-6265 3385);
PAINT MONO (-6265 3385);
DISPLAY INVISIBLE (-6265 3385);
FORCEPROP 1 LASTPIN (-6275 3375) BN 17
J 0
(-6287 3383);
DISPLAY 0.489362 (-6287 3383);
PAINT GREEN (-6287 3383);
FORCEPROP 2 LAST CDS_LIB mstr_standard
J 0
(-6225 3375);
DISPLAY 0.723404 (-6225 3375);
PAINT MONO (-6225 3375);
DISPLAY INVISIBLE (-6225 3375);
FORCEPROP 1 LAST BODY_TYPE PLUMBING
J 0
(-6225 3425);
DISPLAY 0.872340 (-6225 3425);
PAINT GREEN (-6225 3425);
DISPLAY INVISIBLE (-6225 3425);
FORCEPROP 1 LAST HDL_TAP TRUE
J 0
(-5900 3250);
DISPLAY 0.872340 (-5900 3250);
DISPLAY INVISIBLE (-5900 3250);
FORCEPROP 1 LAST PATH I224
J 0
(-6227 3375);
DISPLAY 0.872340 (-6227 3375);
PAINT GREEN (-6227 3375);
DISPLAY INVISIBLE (-6227 3375);
FORCEADD TAP..1
(-6225 3325);
FORCEPROP 3 LASTPIN (-6275 3325) SIG_NAME M_C_CPU0_SB_DQ<16>
J 0
(-6265 3335);
DISPLAY 0.659574 (-6265 3335);
PAINT MONO (-6265 3335);
DISPLAY INVISIBLE (-6265 3335);
FORCEPROP 1 LASTPIN (-6275 3325) BN 16
J 0
(-6287 3333);
DISPLAY 0.489362 (-6287 3333);
PAINT GREEN (-6287 3333);
FORCEPROP 2 LAST CDS_LIB mstr_standard
J 0
(-6225 3325);
DISPLAY 0.723404 (-6225 3325);
PAINT MONO (-6225 3325);
DISPLAY INVISIBLE (-6225 3325);
FORCEPROP 1 LAST BODY_TYPE PLUMBING
J 0
(-6225 3375);
DISPLAY 0.872340 (-6225 3375);
PAINT GREEN (-6225 3375);
DISPLAY INVISIBLE (-6225 3375);
FORCEPROP 1 LAST HDL_TAP TRUE
J 0
(-5900 3200);
DISPLAY 0.872340 (-5900 3200);
DISPLAY INVISIBLE (-5900 3200);
FORCEPROP 1 LAST PATH I225
J 0
(-6227 3325);
DISPLAY 0.872340 (-6227 3325);
PAINT GREEN (-6227 3325);
DISPLAY INVISIBLE (-6227 3325);
FORCEADD TAP..1
(-6225 3575);
FORCEPROP 3 LASTPIN (-6275 3575) SIG_NAME M_C_CPU0_SB_DQ<21>
J 0
(-6265 3585);
DISPLAY 0.659574 (-6265 3585);
PAINT MONO (-6265 3585);
DISPLAY INVISIBLE (-6265 3585);
FORCEPROP 1 LASTPIN (-6275 3575) BN 21
J 0
(-6287 3583);
DISPLAY 0.489362 (-6287 3583);
PAINT GREEN (-6287 3583);
FORCEPROP 2 LAST CDS_LIB mstr_standard
J 0
(-6225 3575);
DISPLAY 0.723404 (-6225 3575);
PAINT MONO (-6225 3575);
DISPLAY INVISIBLE (-6225 3575);
FORCEPROP 1 LAST BODY_TYPE PLUMBING
J 0
(-6225 3625);
DISPLAY 0.872340 (-6225 3625);
PAINT GREEN (-6225 3625);
DISPLAY INVISIBLE (-6225 3625);
FORCEPROP 1 LAST HDL_TAP TRUE
J 0
(-5900 3450);
DISPLAY 0.872340 (-5900 3450);
DISPLAY INVISIBLE (-5900 3450);
FORCEPROP 1 LAST PATH I226
J 0
(-6227 3575);
DISPLAY 0.872340 (-6227 3575);
PAINT GREEN (-6227 3575);
DISPLAY INVISIBLE (-6227 3575);
FORCEADD TAP..1
(-6225 3625);
FORCEPROP 3 LASTPIN (-6275 3625) SIG_NAME M_C_CPU0_SB_DQ<22>
J 0
(-6265 3635);
DISPLAY 0.659574 (-6265 3635);
PAINT MONO (-6265 3635);
DISPLAY INVISIBLE (-6265 3635);
FORCEPROP 1 LASTPIN (-6275 3625) BN 22
J 0
(-6287 3633);
DISPLAY 0.489362 (-6287 3633);
PAINT GREEN (-6287 3633);
FORCEPROP 2 LAST CDS_LIB mstr_standard
J 0
(-6225 3625);
DISPLAY 0.723404 (-6225 3625);
PAINT MONO (-6225 3625);
DISPLAY INVISIBLE (-6225 3625);
FORCEPROP 1 LAST BODY_TYPE PLUMBING
J 0
(-6225 3675);
DISPLAY 0.872340 (-6225 3675);
PAINT GREEN (-6225 3675);
DISPLAY INVISIBLE (-6225 3675);
FORCEPROP 1 LAST HDL_TAP TRUE
J 0
(-5900 3500);
DISPLAY 0.872340 (-5900 3500);
DISPLAY INVISIBLE (-5900 3500);
FORCEPROP 1 LAST PATH I227
J 0
(-6227 3625);
DISPLAY 0.872340 (-6227 3625);
PAINT GREEN (-6227 3625);
DISPLAY INVISIBLE (-6227 3625);
FORCEADD TAP..1
(-6225 3525);
FORCEPROP 3 LASTPIN (-6275 3525) SIG_NAME M_C_CPU0_SB_DQ<20>
J 0
(-6265 3535);
DISPLAY 0.659574 (-6265 3535);
PAINT MONO (-6265 3535);
DISPLAY INVISIBLE (-6265 3535);
FORCEPROP 1 LASTPIN (-6275 3525) BN 20
J 0
(-6287 3533);
DISPLAY 0.489362 (-6287 3533);
PAINT GREEN (-6287 3533);
FORCEPROP 2 LAST CDS_LIB mstr_standard
J 0
(-6225 3525);
DISPLAY 0.723404 (-6225 3525);
PAINT MONO (-6225 3525);
DISPLAY INVISIBLE (-6225 3525);
FORCEPROP 1 LAST BODY_TYPE PLUMBING
J 0
(-6225 3575);
DISPLAY 0.872340 (-6225 3575);
PAINT GREEN (-6225 3575);
DISPLAY INVISIBLE (-6225 3575);
FORCEPROP 1 LAST HDL_TAP TRUE
J 0
(-5900 3400);
DISPLAY 0.872340 (-5900 3400);
DISPLAY INVISIBLE (-5900 3400);
FORCEPROP 1 LAST PATH I228
J 0
(-6227 3525);
DISPLAY 0.872340 (-6227 3525);
PAINT GREEN (-6227 3525);
DISPLAY INVISIBLE (-6227 3525);
FORCEADD TAP..1
(-6225 3675);
FORCEPROP 3 LASTPIN (-6275 3675) SIG_NAME M_C_CPU0_SB_DQ<23>
J 0
(-6265 3685);
DISPLAY 0.659574 (-6265 3685);
PAINT MONO (-6265 3685);
DISPLAY INVISIBLE (-6265 3685);
FORCEPROP 1 LASTPIN (-6275 3675) BN 23
J 0
(-6287 3683);
DISPLAY 0.489362 (-6287 3683);
PAINT GREEN (-6287 3683);
FORCEPROP 2 LAST CDS_LIB mstr_standard
J 0
(-6225 3675);
DISPLAY 0.723404 (-6225 3675);
PAINT MONO (-6225 3675);
DISPLAY INVISIBLE (-6225 3675);
FORCEPROP 1 LAST BODY_TYPE PLUMBING
J 0
(-6225 3725);
DISPLAY 0.872340 (-6225 3725);
PAINT GREEN (-6225 3725);
DISPLAY INVISIBLE (-6225 3725);
FORCEPROP 1 LAST HDL_TAP TRUE
J 0
(-5900 3550);
DISPLAY 0.872340 (-5900 3550);
DISPLAY INVISIBLE (-5900 3550);
FORCEPROP 1 LAST PATH I229
J 0
(-6227 3675);
DISPLAY 0.872340 (-6227 3675);
PAINT GREEN (-6227 3675);
DISPLAY INVISIBLE (-6227 3675);
FORCEADD TAP..1
(-6225 3475);
FORCEPROP 3 LASTPIN (-6275 3475) SIG_NAME M_C_CPU0_SB_DQ<19>
J 0
(-6265 3485);
DISPLAY 0.659574 (-6265 3485);
PAINT MONO (-6265 3485);
DISPLAY INVISIBLE (-6265 3485);
FORCEPROP 1 LASTPIN (-6275 3475) BN 19
J 0
(-6287 3483);
DISPLAY 0.489362 (-6287 3483);
PAINT GREEN (-6287 3483);
FORCEPROP 2 LAST CDS_LIB mstr_standard
J 0
(-6225 3475);
DISPLAY 0.723404 (-6225 3475);
PAINT MONO (-6225 3475);
DISPLAY INVISIBLE (-6225 3475);
FORCEPROP 1 LAST BODY_TYPE PLUMBING
J 0
(-6225 3525);
DISPLAY 0.872340 (-6225 3525);
PAINT GREEN (-6225 3525);
DISPLAY INVISIBLE (-6225 3525);
FORCEPROP 1 LAST HDL_TAP TRUE
J 0
(-5900 3350);
DISPLAY 0.872340 (-5900 3350);
DISPLAY INVISIBLE (-5900 3350);
FORCEPROP 1 LAST PATH I230
J 0
(-6227 3475);
DISPLAY 0.872340 (-6227 3475);
PAINT GREEN (-6227 3475);
DISPLAY INVISIBLE (-6227 3475);
FORCEADD TAP..1
(-6225 3825);
FORCEPROP 3 LASTPIN (-6275 3825) SIG_NAME M_C_CPU0_SB_DQ<26>
J 0
(-6265 3835);
DISPLAY 0.659574 (-6265 3835);
PAINT MONO (-6265 3835);
DISPLAY INVISIBLE (-6265 3835);
FORCEPROP 1 LASTPIN (-6275 3825) BN 26
J 0
(-6287 3833);
DISPLAY 0.489362 (-6287 3833);
PAINT GREEN (-6287 3833);
FORCEPROP 2 LAST CDS_LIB mstr_standard
J 0
(-6225 3825);
DISPLAY 0.723404 (-6225 3825);
PAINT MONO (-6225 3825);
DISPLAY INVISIBLE (-6225 3825);
FORCEPROP 1 LAST BODY_TYPE PLUMBING
J 0
(-6225 3875);
DISPLAY 0.872340 (-6225 3875);
PAINT GREEN (-6225 3875);
DISPLAY INVISIBLE (-6225 3875);
FORCEPROP 1 LAST HDL_TAP TRUE
J 0
(-5900 3700);
DISPLAY 0.872340 (-5900 3700);
DISPLAY INVISIBLE (-5900 3700);
FORCEPROP 1 LAST PATH I231
J 0
(-6227 3825);
DISPLAY 0.872340 (-6227 3825);
PAINT GREEN (-6227 3825);
DISPLAY INVISIBLE (-6227 3825);
FORCEADD TAP..1
(-6225 3875);
FORCEPROP 3 LASTPIN (-6275 3875) SIG_NAME M_C_CPU0_SB_DQ<27>
J 0
(-6265 3885);
DISPLAY 0.659574 (-6265 3885);
PAINT MONO (-6265 3885);
DISPLAY INVISIBLE (-6265 3885);
FORCEPROP 1 LASTPIN (-6275 3875) BN 27
J 0
(-6287 3883);
DISPLAY 0.489362 (-6287 3883);
PAINT GREEN (-6287 3883);
FORCEPROP 2 LAST CDS_LIB mstr_standard
J 0
(-6225 3875);
DISPLAY 0.723404 (-6225 3875);
PAINT MONO (-6225 3875);
DISPLAY INVISIBLE (-6225 3875);
FORCEPROP 1 LAST BODY_TYPE PLUMBING
J 0
(-6225 3925);
DISPLAY 0.872340 (-6225 3925);
PAINT GREEN (-6225 3925);
DISPLAY INVISIBLE (-6225 3925);
FORCEPROP 1 LAST HDL_TAP TRUE
J 0
(-5900 3750);
DISPLAY 0.872340 (-5900 3750);
DISPLAY INVISIBLE (-5900 3750);
FORCEPROP 1 LAST PATH I232
J 0
(-6227 3875);
DISPLAY 0.872340 (-6227 3875);
PAINT GREEN (-6227 3875);
DISPLAY INVISIBLE (-6227 3875);
FORCEADD TAP..1
(-6225 3775);
FORCEPROP 3 LASTPIN (-6275 3775) SIG_NAME M_C_CPU0_SB_DQ<25>
J 0
(-6265 3785);
DISPLAY 0.659574 (-6265 3785);
PAINT MONO (-6265 3785);
DISPLAY INVISIBLE (-6265 3785);
FORCEPROP 1 LASTPIN (-6275 3775) BN 25
J 0
(-6287 3783);
DISPLAY 0.489362 (-6287 3783);
PAINT GREEN (-6287 3783);
FORCEPROP 2 LAST CDS_LIB mstr_standard
J 0
(-6225 3775);
DISPLAY 0.723404 (-6225 3775);
PAINT MONO (-6225 3775);
DISPLAY INVISIBLE (-6225 3775);
FORCEPROP 1 LAST BODY_TYPE PLUMBING
J 0
(-6225 3825);
DISPLAY 0.872340 (-6225 3825);
PAINT GREEN (-6225 3825);
DISPLAY INVISIBLE (-6225 3825);
FORCEPROP 1 LAST HDL_TAP TRUE
J 0
(-5900 3650);
DISPLAY 0.872340 (-5900 3650);
DISPLAY INVISIBLE (-5900 3650);
FORCEPROP 1 LAST PATH I233
J 0
(-6227 3775);
DISPLAY 0.872340 (-6227 3775);
PAINT GREEN (-6227 3775);
DISPLAY INVISIBLE (-6227 3775);
FORCEADD TAP..1
(-6225 3925);
FORCEPROP 3 LASTPIN (-6275 3925) SIG_NAME M_C_CPU0_SB_DQ<28>
J 0
(-6265 3935);
DISPLAY 0.659574 (-6265 3935);
PAINT MONO (-6265 3935);
DISPLAY INVISIBLE (-6265 3935);
FORCEPROP 1 LASTPIN (-6275 3925) BN 28
J 0
(-6287 3933);
DISPLAY 0.489362 (-6287 3933);
PAINT GREEN (-6287 3933);
FORCEPROP 2 LAST CDS_LIB mstr_standard
J 0
(-6225 3925);
DISPLAY 0.723404 (-6225 3925);
PAINT MONO (-6225 3925);
DISPLAY INVISIBLE (-6225 3925);
FORCEPROP 1 LAST BODY_TYPE PLUMBING
J 0
(-6225 3975);
DISPLAY 0.872340 (-6225 3975);
PAINT GREEN (-6225 3975);
DISPLAY INVISIBLE (-6225 3975);
FORCEPROP 1 LAST HDL_TAP TRUE
J 0
(-5900 3800);
DISPLAY 0.872340 (-5900 3800);
DISPLAY INVISIBLE (-5900 3800);
FORCEPROP 1 LAST PATH I234
J 0
(-6227 3925);
DISPLAY 0.872340 (-6227 3925);
PAINT GREEN (-6227 3925);
DISPLAY INVISIBLE (-6227 3925);
FORCEADD TAP..1
(-6225 3725);
FORCEPROP 3 LASTPIN (-6275 3725) SIG_NAME M_C_CPU0_SB_DQ<24>
J 0
(-6265 3735);
DISPLAY 0.659574 (-6265 3735);
PAINT MONO (-6265 3735);
DISPLAY INVISIBLE (-6265 3735);
FORCEPROP 1 LASTPIN (-6275 3725) BN 24
J 0
(-6287 3733);
DISPLAY 0.489362 (-6287 3733);
PAINT GREEN (-6287 3733);
FORCEPROP 2 LAST CDS_LIB mstr_standard
J 0
(-6225 3725);
DISPLAY 0.723404 (-6225 3725);
PAINT MONO (-6225 3725);
DISPLAY INVISIBLE (-6225 3725);
FORCEPROP 1 LAST BODY_TYPE PLUMBING
J 0
(-6225 3775);
DISPLAY 0.872340 (-6225 3775);
PAINT GREEN (-6225 3775);
DISPLAY INVISIBLE (-6225 3775);
FORCEPROP 1 LAST HDL_TAP TRUE
J 0
(-5900 3600);
DISPLAY 0.872340 (-5900 3600);
DISPLAY INVISIBLE (-5900 3600);
FORCEPROP 1 LAST PATH I235
J 0
(-6227 3725);
DISPLAY 0.872340 (-6227 3725);
PAINT GREEN (-6227 3725);
DISPLAY INVISIBLE (-6227 3725);
FORCEADD TAP..1
(-6225 4175);
FORCEPROP 3 LASTPIN (-6275 4175) SIG_NAME M_C_CPU0_SA_DQ<0>
J 0
(-6265 4185);
DISPLAY 0.659574 (-6265 4185);
PAINT MONO (-6265 4185);
DISPLAY INVISIBLE (-6265 4185);
FORCEPROP 1 LASTPIN (-6275 4175) BN 0
J 0
(-6287 4183);
DISPLAY 0.489362 (-6287 4183);
PAINT GREEN (-6287 4183);
FORCEPROP 2 LAST CDS_LIB mstr_standard
J 0
(-6225 4175);
DISPLAY 0.723404 (-6225 4175);
PAINT MONO (-6225 4175);
DISPLAY INVISIBLE (-6225 4175);
FORCEPROP 1 LAST BODY_TYPE PLUMBING
J 0
(-6225 4225);
DISPLAY 0.872340 (-6225 4225);
PAINT GREEN (-6225 4225);
DISPLAY INVISIBLE (-6225 4225);
FORCEPROP 1 LAST HDL_TAP TRUE
J 0
(-5900 4050);
DISPLAY 0.872340 (-5900 4050);
DISPLAY INVISIBLE (-5900 4050);
FORCEPROP 1 LAST PATH I236
J 0
(-6227 4175);
DISPLAY 0.872340 (-6227 4175);
PAINT GREEN (-6227 4175);
DISPLAY INVISIBLE (-6227 4175);
FORCEADD TAP..1
(-6225 4025);
FORCEPROP 3 LASTPIN (-6275 4025) SIG_NAME M_C_CPU0_SB_DQ<30>
J 0
(-6265 4035);
DISPLAY 0.659574 (-6265 4035);
PAINT MONO (-6265 4035);
DISPLAY INVISIBLE (-6265 4035);
FORCEPROP 1 LASTPIN (-6275 4025) BN 30
J 0
(-6287 4033);
DISPLAY 0.489362 (-6287 4033);
PAINT GREEN (-6287 4033);
FORCEPROP 2 LAST CDS_LIB mstr_standard
J 0
(-6225 4025);
DISPLAY 0.723404 (-6225 4025);
PAINT MONO (-6225 4025);
DISPLAY INVISIBLE (-6225 4025);
FORCEPROP 1 LAST BODY_TYPE PLUMBING
J 0
(-6225 4075);
DISPLAY 0.872340 (-6225 4075);
PAINT GREEN (-6225 4075);
DISPLAY INVISIBLE (-6225 4075);
FORCEPROP 1 LAST HDL_TAP TRUE
J 0
(-5900 3900);
DISPLAY 0.872340 (-5900 3900);
DISPLAY INVISIBLE (-5900 3900);
FORCEPROP 1 LAST PATH I237
J 0
(-6227 4025);
DISPLAY 0.872340 (-6227 4025);
PAINT GREEN (-6227 4025);
DISPLAY INVISIBLE (-6227 4025);
FORCEADD TAP..1
(-6225 4075);
FORCEPROP 3 LASTPIN (-6275 4075) SIG_NAME M_C_CPU0_SB_DQ<31>
J 0
(-6265 4085);
DISPLAY 0.659574 (-6265 4085);
PAINT MONO (-6265 4085);
DISPLAY INVISIBLE (-6265 4085);
FORCEPROP 1 LASTPIN (-6275 4075) BN 31
J 0
(-6287 4083);
DISPLAY 0.489362 (-6287 4083);
PAINT GREEN (-6287 4083);
FORCEPROP 2 LAST CDS_LIB mstr_standard
J 0
(-6225 4075);
DISPLAY 0.723404 (-6225 4075);
PAINT MONO (-6225 4075);
DISPLAY INVISIBLE (-6225 4075);
FORCEPROP 1 LAST BODY_TYPE PLUMBING
J 0
(-6225 4125);
DISPLAY 0.872340 (-6225 4125);
PAINT GREEN (-6225 4125);
DISPLAY INVISIBLE (-6225 4125);
FORCEPROP 1 LAST HDL_TAP TRUE
J 0
(-5900 3950);
DISPLAY 0.872340 (-5900 3950);
DISPLAY INVISIBLE (-5900 3950);
FORCEPROP 1 LAST PATH I238
J 0
(-6227 4075);
DISPLAY 0.872340 (-6227 4075);
PAINT GREEN (-6227 4075);
DISPLAY INVISIBLE (-6227 4075);
FORCEADD TAP..1
(-6225 3975);
FORCEPROP 3 LASTPIN (-6275 3975) SIG_NAME M_C_CPU0_SB_DQ<29>
J 0
(-6265 3985);
DISPLAY 0.659574 (-6265 3985);
PAINT MONO (-6265 3985);
DISPLAY INVISIBLE (-6265 3985);
FORCEPROP 1 LASTPIN (-6275 3975) BN 29
J 0
(-6287 3983);
DISPLAY 0.489362 (-6287 3983);
PAINT GREEN (-6287 3983);
FORCEPROP 2 LAST CDS_LIB mstr_standard
J 0
(-6225 3975);
DISPLAY 0.723404 (-6225 3975);
PAINT MONO (-6225 3975);
DISPLAY INVISIBLE (-6225 3975);
FORCEPROP 1 LAST BODY_TYPE PLUMBING
J 0
(-6225 4025);
DISPLAY 0.872340 (-6225 4025);
PAINT GREEN (-6225 4025);
DISPLAY INVISIBLE (-6225 4025);
FORCEPROP 1 LAST HDL_TAP TRUE
J 0
(-5900 3850);
DISPLAY 0.872340 (-5900 3850);
DISPLAY INVISIBLE (-5900 3850);
FORCEPROP 1 LAST PATH I239
J 0
(-6227 3975);
DISPLAY 0.872340 (-6227 3975);
PAINT GREEN (-6227 3975);
DISPLAY INVISIBLE (-6227 3975);
FORCEADD TAP..1
(-6225 4275);
FORCEPROP 3 LASTPIN (-6275 4275) SIG_NAME M_C_CPU0_SA_DQ<2>
J 0
(-6265 4285);
DISPLAY 0.659574 (-6265 4285);
PAINT MONO (-6265 4285);
DISPLAY INVISIBLE (-6265 4285);
FORCEPROP 1 LASTPIN (-6275 4275) BN 2
J 0
(-6287 4283);
DISPLAY 0.489362 (-6287 4283);
PAINT GREEN (-6287 4283);
FORCEPROP 2 LAST CDS_LIB mstr_standard
J 0
(-6225 4275);
DISPLAY 0.723404 (-6225 4275);
PAINT MONO (-6225 4275);
DISPLAY INVISIBLE (-6225 4275);
FORCEPROP 1 LAST BODY_TYPE PLUMBING
J 0
(-6225 4325);
DISPLAY 0.872340 (-6225 4325);
PAINT GREEN (-6225 4325);
DISPLAY INVISIBLE (-6225 4325);
FORCEPROP 1 LAST HDL_TAP TRUE
J 0
(-5900 4150);
DISPLAY 0.872340 (-5900 4150);
DISPLAY INVISIBLE (-5900 4150);
FORCEPROP 1 LAST PATH I240
J 0
(-6227 4275);
DISPLAY 0.872340 (-6227 4275);
PAINT GREEN (-6227 4275);
DISPLAY INVISIBLE (-6227 4275);
FORCEADD TAP..1
(-6225 4225);
FORCEPROP 3 LASTPIN (-6275 4225) SIG_NAME M_C_CPU0_SA_DQ<1>
J 0
(-6265 4235);
DISPLAY 0.659574 (-6265 4235);
PAINT MONO (-6265 4235);
DISPLAY INVISIBLE (-6265 4235);
FORCEPROP 1 LASTPIN (-6275 4225) BN 1
J 0
(-6287 4233);
DISPLAY 0.489362 (-6287 4233);
PAINT GREEN (-6287 4233);
FORCEPROP 2 LAST CDS_LIB mstr_standard
J 0
(-6225 4225);
DISPLAY 0.723404 (-6225 4225);
PAINT MONO (-6225 4225);
DISPLAY INVISIBLE (-6225 4225);
FORCEPROP 1 LAST BODY_TYPE PLUMBING
J 0
(-6225 4275);
DISPLAY 0.872340 (-6225 4275);
PAINT GREEN (-6225 4275);
DISPLAY INVISIBLE (-6225 4275);
FORCEPROP 1 LAST HDL_TAP TRUE
J 0
(-5900 4100);
DISPLAY 0.872340 (-5900 4100);
DISPLAY INVISIBLE (-5900 4100);
FORCEPROP 1 LAST PATH I241
J 0
(-6227 4225);
DISPLAY 0.872340 (-6227 4225);
PAINT GREEN (-6227 4225);
DISPLAY INVISIBLE (-6227 4225);
FORCEADD TAP..1
(-6225 4325);
FORCEPROP 3 LASTPIN (-6275 4325) SIG_NAME M_C_CPU0_SA_DQ<3>
J 0
(-6265 4335);
DISPLAY 0.659574 (-6265 4335);
PAINT MONO (-6265 4335);
DISPLAY INVISIBLE (-6265 4335);
FORCEPROP 1 LASTPIN (-6275 4325) BN 3
J 0
(-6287 4333);
DISPLAY 0.489362 (-6287 4333);
PAINT GREEN (-6287 4333);
FORCEPROP 2 LAST CDS_LIB mstr_standard
J 0
(-6225 4325);
DISPLAY 0.723404 (-6225 4325);
PAINT MONO (-6225 4325);
DISPLAY INVISIBLE (-6225 4325);
FORCEPROP 1 LAST BODY_TYPE PLUMBING
J 0
(-6225 4375);
DISPLAY 0.872340 (-6225 4375);
PAINT GREEN (-6225 4375);
DISPLAY INVISIBLE (-6225 4375);
FORCEPROP 1 LAST HDL_TAP TRUE
J 0
(-5900 4200);
DISPLAY 0.872340 (-5900 4200);
DISPLAY INVISIBLE (-5900 4200);
FORCEPROP 1 LAST PATH I242
J 0
(-6227 4325);
DISPLAY 0.872340 (-6227 4325);
PAINT GREEN (-6227 4325);
DISPLAY INVISIBLE (-6227 4325);
FORCEADD TAP..1
(-6225 4375);
FORCEPROP 3 LASTPIN (-6275 4375) SIG_NAME M_C_CPU0_SA_DQ<4>
J 0
(-6265 4385);
DISPLAY 0.659574 (-6265 4385);
PAINT MONO (-6265 4385);
DISPLAY INVISIBLE (-6265 4385);
FORCEPROP 1 LASTPIN (-6275 4375) BN 4
J 0
(-6287 4383);
DISPLAY 0.489362 (-6287 4383);
PAINT GREEN (-6287 4383);
FORCEPROP 2 LAST CDS_LIB mstr_standard
J 0
(-6225 4375);
DISPLAY 0.723404 (-6225 4375);
PAINT MONO (-6225 4375);
DISPLAY INVISIBLE (-6225 4375);
FORCEPROP 1 LAST BODY_TYPE PLUMBING
J 0
(-6225 4425);
DISPLAY 0.872340 (-6225 4425);
PAINT GREEN (-6225 4425);
DISPLAY INVISIBLE (-6225 4425);
FORCEPROP 1 LAST HDL_TAP TRUE
J 0
(-5900 4250);
DISPLAY 0.872340 (-5900 4250);
DISPLAY INVISIBLE (-5900 4250);
FORCEPROP 1 LAST PATH I243
J 0
(-6227 4375);
DISPLAY 0.872340 (-6227 4375);
PAINT GREEN (-6227 4375);
DISPLAY INVISIBLE (-6227 4375);
FORCEADD TAP..1
(-6225 4425);
FORCEPROP 3 LASTPIN (-6275 4425) SIG_NAME M_C_CPU0_SA_DQ<5>
J 0
(-6265 4435);
DISPLAY 0.659574 (-6265 4435);
PAINT MONO (-6265 4435);
DISPLAY INVISIBLE (-6265 4435);
FORCEPROP 1 LASTPIN (-6275 4425) BN 5
J 0
(-6287 4433);
DISPLAY 0.489362 (-6287 4433);
PAINT GREEN (-6287 4433);
FORCEPROP 2 LAST CDS_LIB mstr_standard
J 0
(-6225 4425);
DISPLAY 0.723404 (-6225 4425);
PAINT MONO (-6225 4425);
DISPLAY INVISIBLE (-6225 4425);
FORCEPROP 1 LAST BODY_TYPE PLUMBING
J 0
(-6225 4475);
DISPLAY 0.872340 (-6225 4475);
PAINT GREEN (-6225 4475);
DISPLAY INVISIBLE (-6225 4475);
FORCEPROP 1 LAST HDL_TAP TRUE
J 0
(-5900 4300);
DISPLAY 0.872340 (-5900 4300);
DISPLAY INVISIBLE (-5900 4300);
FORCEPROP 1 LAST PATH I244
J 0
(-6227 4425);
DISPLAY 0.872340 (-6227 4425);
PAINT GREEN (-6227 4425);
DISPLAY INVISIBLE (-6227 4425);
FORCEADD TAP..1
(-6225 4525);
FORCEPROP 3 LASTPIN (-6275 4525) SIG_NAME M_C_CPU0_SA_DQ<7>
J 0
(-6265 4535);
DISPLAY 0.659574 (-6265 4535);
PAINT MONO (-6265 4535);
DISPLAY INVISIBLE (-6265 4535);
FORCEPROP 1 LASTPIN (-6275 4525) BN 7
J 0
(-6287 4533);
DISPLAY 0.489362 (-6287 4533);
PAINT GREEN (-6287 4533);
FORCEPROP 2 LAST CDS_LIB mstr_standard
J 0
(-6225 4525);
DISPLAY 0.723404 (-6225 4525);
PAINT MONO (-6225 4525);
DISPLAY INVISIBLE (-6225 4525);
FORCEPROP 1 LAST BODY_TYPE PLUMBING
J 0
(-6225 4575);
DISPLAY 0.872340 (-6225 4575);
PAINT GREEN (-6225 4575);
DISPLAY INVISIBLE (-6225 4575);
FORCEPROP 1 LAST HDL_TAP TRUE
J 0
(-5900 4400);
DISPLAY 0.872340 (-5900 4400);
DISPLAY INVISIBLE (-5900 4400);
FORCEPROP 1 LAST PATH I245
J 0
(-6227 4525);
DISPLAY 0.872340 (-6227 4525);
PAINT GREEN (-6227 4525);
DISPLAY INVISIBLE (-6227 4525);
FORCEADD TAP..1
(-6225 4475);
FORCEPROP 3 LASTPIN (-6275 4475) SIG_NAME M_C_CPU0_SA_DQ<6>
J 0
(-6265 4485);
DISPLAY 0.659574 (-6265 4485);
PAINT MONO (-6265 4485);
DISPLAY INVISIBLE (-6265 4485);
FORCEPROP 1 LASTPIN (-6275 4475) BN 6
J 0
(-6287 4483);
DISPLAY 0.489362 (-6287 4483);
PAINT GREEN (-6287 4483);
FORCEPROP 2 LAST CDS_LIB mstr_standard
J 0
(-6225 4475);
DISPLAY 0.723404 (-6225 4475);
PAINT MONO (-6225 4475);
DISPLAY INVISIBLE (-6225 4475);
FORCEPROP 1 LAST BODY_TYPE PLUMBING
J 0
(-6225 4525);
DISPLAY 0.872340 (-6225 4525);
PAINT GREEN (-6225 4525);
DISPLAY INVISIBLE (-6225 4525);
FORCEPROP 1 LAST HDL_TAP TRUE
J 0
(-5900 4350);
DISPLAY 0.872340 (-5900 4350);
DISPLAY INVISIBLE (-5900 4350);
FORCEPROP 1 LAST PATH I246
J 0
(-6227 4475);
DISPLAY 0.872340 (-6227 4475);
PAINT GREEN (-6227 4475);
DISPLAY INVISIBLE (-6227 4475);
FORCEADD TAP..1
(-6225 4575);
FORCEPROP 3 LASTPIN (-6275 4575) SIG_NAME M_C_CPU0_SA_DQ<8>
J 0
(-6265 4585);
DISPLAY 0.659574 (-6265 4585);
PAINT MONO (-6265 4585);
DISPLAY INVISIBLE (-6265 4585);
FORCEPROP 1 LASTPIN (-6275 4575) BN 8
J 0
(-6287 4583);
DISPLAY 0.489362 (-6287 4583);
PAINT GREEN (-6287 4583);
FORCEPROP 2 LAST CDS_LIB mstr_standard
J 0
(-6225 4575);
DISPLAY 0.723404 (-6225 4575);
PAINT MONO (-6225 4575);
DISPLAY INVISIBLE (-6225 4575);
FORCEPROP 1 LAST BODY_TYPE PLUMBING
J 0
(-6225 4625);
DISPLAY 0.872340 (-6225 4625);
PAINT GREEN (-6225 4625);
DISPLAY INVISIBLE (-6225 4625);
FORCEPROP 1 LAST HDL_TAP TRUE
J 0
(-5900 4450);
DISPLAY 0.872340 (-5900 4450);
DISPLAY INVISIBLE (-5900 4450);
FORCEPROP 1 LAST PATH I247
J 0
(-6227 4575);
DISPLAY 0.872340 (-6227 4575);
PAINT GREEN (-6227 4575);
DISPLAY INVISIBLE (-6227 4575);
FORCEADD TAP..1
(-6225 4625);
FORCEPROP 3 LASTPIN (-6275 4625) SIG_NAME M_C_CPU0_SA_DQ<9>
J 0
(-6265 4635);
DISPLAY 0.659574 (-6265 4635);
PAINT MONO (-6265 4635);
DISPLAY INVISIBLE (-6265 4635);
FORCEPROP 1 LASTPIN (-6275 4625) BN 9
J 0
(-6287 4633);
DISPLAY 0.489362 (-6287 4633);
PAINT GREEN (-6287 4633);
FORCEPROP 2 LAST CDS_LIB mstr_standard
J 0
(-6225 4625);
DISPLAY 0.723404 (-6225 4625);
PAINT MONO (-6225 4625);
DISPLAY INVISIBLE (-6225 4625);
FORCEPROP 1 LAST BODY_TYPE PLUMBING
J 0
(-6225 4675);
DISPLAY 0.872340 (-6225 4675);
PAINT GREEN (-6225 4675);
DISPLAY INVISIBLE (-6225 4675);
FORCEPROP 1 LAST HDL_TAP TRUE
J 0
(-5900 4500);
DISPLAY 0.872340 (-5900 4500);
DISPLAY INVISIBLE (-5900 4500);
FORCEPROP 1 LAST PATH I248
J 0
(-6227 4625);
DISPLAY 0.872340 (-6227 4625);
PAINT GREEN (-6227 4625);
DISPLAY INVISIBLE (-6227 4625);
FORCEADD TAP..1
(-6225 4675);
FORCEPROP 3 LASTPIN (-6275 4675) SIG_NAME M_C_CPU0_SA_DQ<10>
J 0
(-6265 4685);
DISPLAY 0.659574 (-6265 4685);
PAINT MONO (-6265 4685);
DISPLAY INVISIBLE (-6265 4685);
FORCEPROP 1 LASTPIN (-6275 4675) BN 10
J 0
(-6287 4683);
DISPLAY 0.489362 (-6287 4683);
PAINT GREEN (-6287 4683);
FORCEPROP 2 LAST CDS_LIB mstr_standard
J 0
(-6225 4675);
DISPLAY 0.723404 (-6225 4675);
PAINT MONO (-6225 4675);
DISPLAY INVISIBLE (-6225 4675);
FORCEPROP 1 LAST BODY_TYPE PLUMBING
J 0
(-6225 4725);
DISPLAY 0.872340 (-6225 4725);
PAINT GREEN (-6225 4725);
DISPLAY INVISIBLE (-6225 4725);
FORCEPROP 1 LAST HDL_TAP TRUE
J 0
(-5900 4550);
DISPLAY 0.872340 (-5900 4550);
DISPLAY INVISIBLE (-5900 4550);
FORCEPROP 1 LAST PATH I249
J 0
(-6227 4675);
DISPLAY 0.872340 (-6227 4675);
PAINT GREEN (-6227 4675);
DISPLAY INVISIBLE (-6227 4675);
FORCEADD TAP..1
(-6225 4875);
FORCEPROP 3 LASTPIN (-6275 4875) SIG_NAME M_C_CPU0_SA_DQ<14>
J 0
(-6265 4885);
DISPLAY 0.659574 (-6265 4885);
PAINT MONO (-6265 4885);
DISPLAY INVISIBLE (-6265 4885);
FORCEPROP 1 LASTPIN (-6275 4875) BN 14
J 0
(-6287 4883);
DISPLAY 0.489362 (-6287 4883);
PAINT GREEN (-6287 4883);
FORCEPROP 2 LAST CDS_LIB mstr_standard
J 0
(-6225 4875);
DISPLAY 0.723404 (-6225 4875);
PAINT MONO (-6225 4875);
DISPLAY INVISIBLE (-6225 4875);
FORCEPROP 1 LAST BODY_TYPE PLUMBING
J 0
(-6225 4925);
DISPLAY 0.872340 (-6225 4925);
PAINT GREEN (-6225 4925);
DISPLAY INVISIBLE (-6225 4925);
FORCEPROP 1 LAST HDL_TAP TRUE
J 0
(-5900 4750);
DISPLAY 0.872340 (-5900 4750);
DISPLAY INVISIBLE (-5900 4750);
FORCEPROP 1 LAST PATH I250
J 0
(-6227 4875);
DISPLAY 0.872340 (-6227 4875);
PAINT GREEN (-6227 4875);
DISPLAY INVISIBLE (-6227 4875);
FORCEADD TAP..1
(-6225 4925);
FORCEPROP 3 LASTPIN (-6275 4925) SIG_NAME M_C_CPU0_SA_DQ<15>
J 0
(-6265 4935);
DISPLAY 0.659574 (-6265 4935);
PAINT MONO (-6265 4935);
DISPLAY INVISIBLE (-6265 4935);
FORCEPROP 1 LASTPIN (-6275 4925) BN 15
J 0
(-6287 4933);
DISPLAY 0.489362 (-6287 4933);
PAINT GREEN (-6287 4933);
FORCEPROP 2 LAST CDS_LIB mstr_standard
J 0
(-6225 4925);
DISPLAY 0.723404 (-6225 4925);
PAINT MONO (-6225 4925);
DISPLAY INVISIBLE (-6225 4925);
FORCEPROP 1 LAST BODY_TYPE PLUMBING
J 0
(-6225 4975);
DISPLAY 0.872340 (-6225 4975);
PAINT GREEN (-6225 4975);
DISPLAY INVISIBLE (-6225 4975);
FORCEPROP 1 LAST HDL_TAP TRUE
J 0
(-5900 4800);
DISPLAY 0.872340 (-5900 4800);
DISPLAY INVISIBLE (-5900 4800);
FORCEPROP 1 LAST PATH I251
J 0
(-6227 4925);
DISPLAY 0.872340 (-6227 4925);
PAINT GREEN (-6227 4925);
DISPLAY INVISIBLE (-6227 4925);
FORCEADD TAP..1
(-6225 4825);
FORCEPROP 3 LASTPIN (-6275 4825) SIG_NAME M_C_CPU0_SA_DQ<13>
J 0
(-6265 4835);
DISPLAY 0.659574 (-6265 4835);
PAINT MONO (-6265 4835);
DISPLAY INVISIBLE (-6265 4835);
FORCEPROP 1 LASTPIN (-6275 4825) BN 13
J 0
(-6287 4833);
DISPLAY 0.489362 (-6287 4833);
PAINT GREEN (-6287 4833);
FORCEPROP 2 LAST CDS_LIB mstr_standard
J 0
(-6225 4825);
DISPLAY 0.723404 (-6225 4825);
PAINT MONO (-6225 4825);
DISPLAY INVISIBLE (-6225 4825);
FORCEPROP 1 LAST BODY_TYPE PLUMBING
J 0
(-6225 4875);
DISPLAY 0.872340 (-6225 4875);
PAINT GREEN (-6225 4875);
DISPLAY INVISIBLE (-6225 4875);
FORCEPROP 1 LAST HDL_TAP TRUE
J 0
(-5900 4700);
DISPLAY 0.872340 (-5900 4700);
DISPLAY INVISIBLE (-5900 4700);
FORCEPROP 1 LAST PATH I252
J 0
(-6227 4825);
DISPLAY 0.872340 (-6227 4825);
PAINT GREEN (-6227 4825);
DISPLAY INVISIBLE (-6227 4825);
FORCEADD TAP..1
(-6225 4775);
FORCEPROP 3 LASTPIN (-6275 4775) SIG_NAME M_C_CPU0_SA_DQ<12>
J 0
(-6265 4785);
DISPLAY 0.659574 (-6265 4785);
PAINT MONO (-6265 4785);
DISPLAY INVISIBLE (-6265 4785);
FORCEPROP 1 LASTPIN (-6275 4775) BN 12
J 0
(-6287 4783);
DISPLAY 0.489362 (-6287 4783);
PAINT GREEN (-6287 4783);
FORCEPROP 2 LAST CDS_LIB mstr_standard
J 0
(-6225 4775);
DISPLAY 0.723404 (-6225 4775);
PAINT MONO (-6225 4775);
DISPLAY INVISIBLE (-6225 4775);
FORCEPROP 1 LAST BODY_TYPE PLUMBING
J 0
(-6225 4825);
DISPLAY 0.872340 (-6225 4825);
PAINT GREEN (-6225 4825);
DISPLAY INVISIBLE (-6225 4825);
FORCEPROP 1 LAST HDL_TAP TRUE
J 0
(-5900 4650);
DISPLAY 0.872340 (-5900 4650);
DISPLAY INVISIBLE (-5900 4650);
FORCEPROP 1 LAST PATH I253
J 0
(-6227 4775);
DISPLAY 0.872340 (-6227 4775);
PAINT GREEN (-6227 4775);
DISPLAY INVISIBLE (-6227 4775);
FORCEADD TAP..1
(-6225 4725);
FORCEPROP 3 LASTPIN (-6275 4725) SIG_NAME M_C_CPU0_SA_DQ<11>
J 0
(-6265 4735);
DISPLAY 0.659574 (-6265 4735);
PAINT MONO (-6265 4735);
DISPLAY INVISIBLE (-6265 4735);
FORCEPROP 1 LASTPIN (-6275 4725) BN 11
J 0
(-6287 4733);
DISPLAY 0.489362 (-6287 4733);
PAINT GREEN (-6287 4733);
FORCEPROP 2 LAST CDS_LIB mstr_standard
J 0
(-6225 4725);
DISPLAY 0.723404 (-6225 4725);
PAINT MONO (-6225 4725);
DISPLAY INVISIBLE (-6225 4725);
FORCEPROP 1 LAST BODY_TYPE PLUMBING
J 0
(-6225 4775);
DISPLAY 0.872340 (-6225 4775);
PAINT GREEN (-6225 4775);
DISPLAY INVISIBLE (-6225 4775);
FORCEPROP 1 LAST HDL_TAP TRUE
J 0
(-5900 4600);
DISPLAY 0.872340 (-5900 4600);
DISPLAY INVISIBLE (-5900 4600);
FORCEPROP 1 LAST PATH I254
J 0
(-6227 4725);
DISPLAY 0.872340 (-6227 4725);
PAINT GREEN (-6227 4725);
DISPLAY INVISIBLE (-6227 4725);
FORCEADD TAP..1
(-6225 5025);
FORCEPROP 3 LASTPIN (-6275 5025) SIG_NAME M_C_CPU0_SA_DQ<17>
J 0
(-6265 5035);
DISPLAY 0.659574 (-6265 5035);
PAINT MONO (-6265 5035);
DISPLAY INVISIBLE (-6265 5035);
FORCEPROP 1 LASTPIN (-6275 5025) BN 17
J 0
(-6287 5033);
DISPLAY 0.489362 (-6287 5033);
PAINT GREEN (-6287 5033);
FORCEPROP 2 LAST CDS_LIB mstr_standard
J 0
(-6225 5025);
DISPLAY 0.723404 (-6225 5025);
PAINT MONO (-6225 5025);
DISPLAY INVISIBLE (-6225 5025);
FORCEPROP 1 LAST BODY_TYPE PLUMBING
J 0
(-6225 5075);
DISPLAY 0.872340 (-6225 5075);
PAINT GREEN (-6225 5075);
DISPLAY INVISIBLE (-6225 5075);
FORCEPROP 1 LAST HDL_TAP TRUE
J 0
(-5900 4900);
DISPLAY 0.872340 (-5900 4900);
DISPLAY INVISIBLE (-5900 4900);
FORCEPROP 1 LAST PATH I255
J 0
(-6227 5025);
DISPLAY 0.872340 (-6227 5025);
PAINT GREEN (-6227 5025);
DISPLAY INVISIBLE (-6227 5025);
FORCEADD TAP..1
(-6225 5075);
FORCEPROP 3 LASTPIN (-6275 5075) SIG_NAME M_C_CPU0_SA_DQ<18>
J 0
(-6265 5085);
DISPLAY 0.659574 (-6265 5085);
PAINT MONO (-6265 5085);
DISPLAY INVISIBLE (-6265 5085);
FORCEPROP 1 LASTPIN (-6275 5075) BN 18
J 0
(-6287 5083);
DISPLAY 0.489362 (-6287 5083);
PAINT GREEN (-6287 5083);
FORCEPROP 2 LAST CDS_LIB mstr_standard
J 0
(-6225 5075);
DISPLAY 0.723404 (-6225 5075);
PAINT MONO (-6225 5075);
DISPLAY INVISIBLE (-6225 5075);
FORCEPROP 1 LAST BODY_TYPE PLUMBING
J 0
(-6225 5125);
DISPLAY 0.872340 (-6225 5125);
PAINT GREEN (-6225 5125);
DISPLAY INVISIBLE (-6225 5125);
FORCEPROP 1 LAST HDL_TAP TRUE
J 0
(-5900 4950);
DISPLAY 0.872340 (-5900 4950);
DISPLAY INVISIBLE (-5900 4950);
FORCEPROP 1 LAST PATH I256
J 0
(-6227 5075);
DISPLAY 0.872340 (-6227 5075);
PAINT GREEN (-6227 5075);
DISPLAY INVISIBLE (-6227 5075);
FORCEADD TAP..1
(-6225 4975);
FORCEPROP 3 LASTPIN (-6275 4975) SIG_NAME M_C_CPU0_SA_DQ<16>
J 0
(-6265 4985);
DISPLAY 0.659574 (-6265 4985);
PAINT MONO (-6265 4985);
DISPLAY INVISIBLE (-6265 4985);
FORCEPROP 1 LASTPIN (-6275 4975) BN 16
J 0
(-6287 4983);
DISPLAY 0.489362 (-6287 4983);
PAINT GREEN (-6287 4983);
FORCEPROP 2 LAST CDS_LIB mstr_standard
J 0
(-6225 4975);
DISPLAY 0.723404 (-6225 4975);
PAINT MONO (-6225 4975);
DISPLAY INVISIBLE (-6225 4975);
FORCEPROP 1 LAST BODY_TYPE PLUMBING
J 0
(-6225 5025);
DISPLAY 0.872340 (-6225 5025);
PAINT GREEN (-6225 5025);
DISPLAY INVISIBLE (-6225 5025);
FORCEPROP 1 LAST HDL_TAP TRUE
J 0
(-5900 4850);
DISPLAY 0.872340 (-5900 4850);
DISPLAY INVISIBLE (-5900 4850);
FORCEPROP 1 LAST PATH I257
J 0
(-6227 4975);
DISPLAY 0.872340 (-6227 4975);
PAINT GREEN (-6227 4975);
DISPLAY INVISIBLE (-6227 4975);
FORCEADD TAP..1
(-6225 5175);
FORCEPROP 3 LASTPIN (-6275 5175) SIG_NAME M_C_CPU0_SA_DQ<20>
J 0
(-6265 5185);
DISPLAY 0.659574 (-6265 5185);
PAINT MONO (-6265 5185);
DISPLAY INVISIBLE (-6265 5185);
FORCEPROP 1 LASTPIN (-6275 5175) BN 20
J 0
(-6287 5183);
DISPLAY 0.489362 (-6287 5183);
PAINT GREEN (-6287 5183);
FORCEPROP 2 LAST CDS_LIB mstr_standard
J 0
(-6225 5175);
DISPLAY 0.723404 (-6225 5175);
PAINT MONO (-6225 5175);
DISPLAY INVISIBLE (-6225 5175);
FORCEPROP 1 LAST BODY_TYPE PLUMBING
J 0
(-6225 5225);
DISPLAY 0.872340 (-6225 5225);
PAINT GREEN (-6225 5225);
DISPLAY INVISIBLE (-6225 5225);
FORCEPROP 1 LAST HDL_TAP TRUE
J 0
(-5900 5050);
DISPLAY 0.872340 (-5900 5050);
DISPLAY INVISIBLE (-5900 5050);
FORCEPROP 1 LAST PATH I258
J 0
(-6227 5175);
DISPLAY 0.872340 (-6227 5175);
PAINT GREEN (-6227 5175);
DISPLAY INVISIBLE (-6227 5175);
FORCEADD TAP..1
(-6225 5125);
FORCEPROP 3 LASTPIN (-6275 5125) SIG_NAME M_C_CPU0_SA_DQ<19>
J 0
(-6265 5135);
DISPLAY 0.659574 (-6265 5135);
PAINT MONO (-6265 5135);
DISPLAY INVISIBLE (-6265 5135);
FORCEPROP 1 LASTPIN (-6275 5125) BN 19
J 0
(-6287 5133);
DISPLAY 0.489362 (-6287 5133);
PAINT GREEN (-6287 5133);
FORCEPROP 2 LAST CDS_LIB mstr_standard
J 0
(-6225 5125);
DISPLAY 0.723404 (-6225 5125);
PAINT MONO (-6225 5125);
DISPLAY INVISIBLE (-6225 5125);
FORCEPROP 1 LAST BODY_TYPE PLUMBING
J 0
(-6225 5175);
DISPLAY 0.872340 (-6225 5175);
PAINT GREEN (-6225 5175);
DISPLAY INVISIBLE (-6225 5175);
FORCEPROP 1 LAST HDL_TAP TRUE
J 0
(-5900 5000);
DISPLAY 0.872340 (-5900 5000);
DISPLAY INVISIBLE (-5900 5000);
FORCEPROP 1 LAST PATH I259
J 0
(-6227 5125);
DISPLAY 0.872340 (-6227 5125);
PAINT GREEN (-6227 5125);
DISPLAY INVISIBLE (-6227 5125);
FORCEADD OFFPAGE..3
(-5675 4125);
FORCEPROP 2 LAST $XR0 12 
J 0
(-5461 4125);
DISPLAY 0.638298 (-5461 4125);
PAINT MONO (-5461 4125);
FORCEPROP 2 LAST PATH I260
J 0
(-5350 4175);
DISPLAY 0.808511 (-5350 4175);
DISPLAY INVISIBLE (-5350 4175);
FORCEPROP 1 LAST COMMENT_BODY TRUE
J 0
(-5725 4025);
DISPLAY 0.872340 (-5725 4025);
PAINT GREEN (-5725 4025);
DISPLAY INVISIBLE (-5725 4025);
FORCEPROP 1 LAST OFFPAGE TRUE
J 0
(-5350 4000);
DISPLAY 0.872340 (-5350 4000);
PAINT GREEN (-5350 4000);
DISPLAY INVISIBLE (-5350 4000);
FORCEPROP 2 LAST CDS_LIB mstr_standard
J 0
(-5675 4125);
DISPLAY 0.723404 (-5675 4125);
PAINT MONO (-5675 4125);
DISPLAY INVISIBLE (-5675 4125);
FORCEADD OFFPAGE..1
(-8525 5375);
FORCEPROP 2 LAST $XR0 12 
J 0
(-8746 5375);
DISPLAY 0.638298 (-8746 5375);
PAINT MONO (-8746 5375);
FORCEPROP 2 LAST PATH I261
J 0
(-8475 5450);
DISPLAY 0.808511 (-8475 5450);
DISPLAY INVISIBLE (-8475 5450);
FORCEPROP 1 LAST COMMENT_BODY TRUE
J 0
(-8400 5275);
DISPLAY 0.872340 (-8400 5275);
PAINT GREEN (-8400 5275);
DISPLAY INVISIBLE (-8400 5275);
FORCEPROP 1 LAST OFFPAGE TRUE
J 0
(-8200 5250);
DISPLAY 0.872340 (-8200 5250);
PAINT GREEN (-8200 5250);
DISPLAY INVISIBLE (-8200 5250);
FORCEPROP 2 LAST CDS_LIB mstr_standard
J 0
(-8525 5375);
DISPLAY 0.723404 (-8525 5375);
PAINT MONO (-8525 5375);
DISPLAY INVISIBLE (-8525 5375);
FORCEADD OFFPAGE..1
(-8525 5775);
FORCEPROP 2 LAST $XR0 12 
J 0
(-8746 5775);
DISPLAY 0.638298 (-8746 5775);
PAINT MONO (-8746 5775);
FORCEPROP 2 LAST PATH I262
J 0
(-8475 5850);
DISPLAY 0.808511 (-8475 5850);
DISPLAY INVISIBLE (-8475 5850);
FORCEPROP 1 LAST COMMENT_BODY TRUE
J 0
(-8400 5675);
DISPLAY 0.872340 (-8400 5675);
PAINT GREEN (-8400 5675);
DISPLAY INVISIBLE (-8400 5675);
FORCEPROP 1 LAST OFFPAGE TRUE
J 0
(-8200 5650);
DISPLAY 0.872340 (-8200 5650);
PAINT GREEN (-8200 5650);
DISPLAY INVISIBLE (-8200 5650);
FORCEPROP 2 LAST CDS_LIB mstr_standard
J 0
(-8525 5775);
DISPLAY 0.723404 (-8525 5775);
PAINT MONO (-8525 5775);
DISPLAY INVISIBLE (-8525 5775);
FORCEADD TAP..1
R 2
(-7925 5325);
FORCEPROP 3 LASTPIN (-7875 5325) SIG_NAME M_C_CPU0_SB_CA<6>
J 0
(-7865 5335);
DISPLAY 0.659574 (-7865 5335);
PAINT MONO (-7865 5335);
DISPLAY INVISIBLE (-7865 5335);
FORCEPROP 1 LASTPIN (-7875 5325) BN 6
J 2
(-7863 5333);
DISPLAY 0.489362 (-7863 5333);
PAINT GREEN (-7863 5333);
FORCEPROP 2 LAST CDS_LIB mstr_standard
J 0
(-7925 5325);
DISPLAY 0.723404 (-7925 5325);
PAINT MONO (-7925 5325);
DISPLAY INVISIBLE (-7925 5325);
FORCEPROP 1 LAST BODY_TYPE PLUMBING
J 2
(-7925 5375);
DISPLAY 0.872340 (-7925 5375);
PAINT GREEN (-7925 5375);
DISPLAY INVISIBLE (-7925 5375);
FORCEPROP 1 LAST HDL_TAP TRUE
J 2
(-8250 5200);
DISPLAY 0.872340 (-8250 5200);
DISPLAY INVISIBLE (-8250 5200);
FORCEPROP 1 LAST PATH I263
J 2
(-7923 5325);
DISPLAY 0.872340 (-7923 5325);
PAINT GREEN (-7923 5325);
DISPLAY INVISIBLE (-7923 5325);
FORCEADD TAP..1
R 2
(-7925 5225);
FORCEPROP 3 LASTPIN (-7875 5225) SIG_NAME M_C_CPU0_SB_CA<4>
J 0
(-7865 5235);
DISPLAY 0.659574 (-7865 5235);
PAINT MONO (-7865 5235);
DISPLAY INVISIBLE (-7865 5235);
FORCEPROP 1 LASTPIN (-7875 5225) BN 4
J 2
(-7863 5233);
DISPLAY 0.489362 (-7863 5233);
PAINT GREEN (-7863 5233);
FORCEPROP 2 LAST CDS_LIB mstr_standard
J 0
(-7925 5225);
DISPLAY 0.723404 (-7925 5225);
PAINT MONO (-7925 5225);
DISPLAY INVISIBLE (-7925 5225);
FORCEPROP 1 LAST BODY_TYPE PLUMBING
J 2
(-7925 5275);
DISPLAY 0.872340 (-7925 5275);
PAINT GREEN (-7925 5275);
DISPLAY INVISIBLE (-7925 5275);
FORCEPROP 1 LAST HDL_TAP TRUE
J 2
(-8250 5100);
DISPLAY 0.872340 (-8250 5100);
DISPLAY INVISIBLE (-8250 5100);
FORCEPROP 1 LAST PATH I264
J 2
(-7923 5225);
DISPLAY 0.872340 (-7923 5225);
PAINT GREEN (-7923 5225);
DISPLAY INVISIBLE (-7923 5225);
FORCEADD TAP..1
R 2
(-7925 5275);
FORCEPROP 3 LASTPIN (-7875 5275) SIG_NAME M_C_CPU0_SB_CA<5>
J 0
(-7865 5285);
DISPLAY 0.659574 (-7865 5285);
PAINT MONO (-7865 5285);
DISPLAY INVISIBLE (-7865 5285);
FORCEPROP 1 LASTPIN (-7875 5275) BN 5
J 2
(-7863 5283);
DISPLAY 0.489362 (-7863 5283);
PAINT GREEN (-7863 5283);
FORCEPROP 2 LAST CDS_LIB mstr_standard
J 0
(-7925 5275);
DISPLAY 0.723404 (-7925 5275);
PAINT MONO (-7925 5275);
DISPLAY INVISIBLE (-7925 5275);
FORCEPROP 1 LAST BODY_TYPE PLUMBING
J 2
(-7925 5325);
DISPLAY 0.872340 (-7925 5325);
PAINT GREEN (-7925 5325);
DISPLAY INVISIBLE (-7925 5325);
FORCEPROP 1 LAST HDL_TAP TRUE
J 2
(-8250 5150);
DISPLAY 0.872340 (-8250 5150);
DISPLAY INVISIBLE (-8250 5150);
FORCEPROP 1 LAST PATH I265
J 2
(-7923 5275);
DISPLAY 0.872340 (-7923 5275);
PAINT GREEN (-7923 5275);
DISPLAY INVISIBLE (-7923 5275);
FORCEADD TAP..1
R 2
(-7925 5425);
FORCEPROP 3 LASTPIN (-7875 5425) SIG_NAME M_C_CPU0_SA_CA<0>
J 0
(-7865 5435);
DISPLAY 0.659574 (-7865 5435);
PAINT MONO (-7865 5435);
DISPLAY INVISIBLE (-7865 5435);
FORCEPROP 1 LASTPIN (-7875 5425) BN 0
J 2
(-7863 5433);
DISPLAY 0.489362 (-7863 5433);
PAINT GREEN (-7863 5433);
FORCEPROP 2 LAST CDS_LIB mstr_standard
J 0
(-7925 5425);
DISPLAY 0.723404 (-7925 5425);
PAINT MONO (-7925 5425);
DISPLAY INVISIBLE (-7925 5425);
FORCEPROP 1 LAST BODY_TYPE PLUMBING
J 2
(-7925 5475);
DISPLAY 0.872340 (-7925 5475);
PAINT GREEN (-7925 5475);
DISPLAY INVISIBLE (-7925 5475);
FORCEPROP 1 LAST HDL_TAP TRUE
J 2
(-8250 5300);
DISPLAY 0.872340 (-8250 5300);
DISPLAY INVISIBLE (-8250 5300);
FORCEPROP 1 LAST PATH I266
J 2
(-7923 5425);
DISPLAY 0.872340 (-7923 5425);
PAINT GREEN (-7923 5425);
DISPLAY INVISIBLE (-7923 5425);
FORCEADD TAP..1
R 2
(-7925 5475);
FORCEPROP 3 LASTPIN (-7875 5475) SIG_NAME M_C_CPU0_SA_CA<1>
J 0
(-7865 5485);
DISPLAY 0.659574 (-7865 5485);
PAINT MONO (-7865 5485);
DISPLAY INVISIBLE (-7865 5485);
FORCEPROP 1 LASTPIN (-7875 5475) BN 1
J 2
(-7863 5483);
DISPLAY 0.489362 (-7863 5483);
PAINT GREEN (-7863 5483);
FORCEPROP 2 LAST CDS_LIB mstr_standard
J 0
(-7925 5475);
DISPLAY 0.723404 (-7925 5475);
PAINT MONO (-7925 5475);
DISPLAY INVISIBLE (-7925 5475);
FORCEPROP 1 LAST BODY_TYPE PLUMBING
J 2
(-7925 5525);
DISPLAY 0.872340 (-7925 5525);
PAINT GREEN (-7925 5525);
DISPLAY INVISIBLE (-7925 5525);
FORCEPROP 1 LAST HDL_TAP TRUE
J 2
(-8250 5350);
DISPLAY 0.872340 (-8250 5350);
DISPLAY INVISIBLE (-8250 5350);
FORCEPROP 1 LAST PATH I267
J 2
(-7923 5475);
DISPLAY 0.872340 (-7923 5475);
PAINT GREEN (-7923 5475);
DISPLAY INVISIBLE (-7923 5475);
FORCEADD TAP..1
R 2
(-7925 5525);
FORCEPROP 3 LASTPIN (-7875 5525) SIG_NAME M_C_CPU0_SA_CA<2>
J 0
(-7865 5535);
DISPLAY 0.659574 (-7865 5535);
PAINT MONO (-7865 5535);
DISPLAY INVISIBLE (-7865 5535);
FORCEPROP 1 LASTPIN (-7875 5525) BN 2
J 2
(-7863 5533);
DISPLAY 0.489362 (-7863 5533);
PAINT GREEN (-7863 5533);
FORCEPROP 2 LAST CDS_LIB mstr_standard
J 0
(-7925 5525);
DISPLAY 0.723404 (-7925 5525);
PAINT MONO (-7925 5525);
DISPLAY INVISIBLE (-7925 5525);
FORCEPROP 1 LAST BODY_TYPE PLUMBING
J 2
(-7925 5575);
DISPLAY 0.872340 (-7925 5575);
PAINT GREEN (-7925 5575);
DISPLAY INVISIBLE (-7925 5575);
FORCEPROP 1 LAST HDL_TAP TRUE
J 2
(-8250 5400);
DISPLAY 0.872340 (-8250 5400);
DISPLAY INVISIBLE (-8250 5400);
FORCEPROP 1 LAST PATH I268
J 2
(-7923 5525);
DISPLAY 0.872340 (-7923 5525);
PAINT GREEN (-7923 5525);
DISPLAY INVISIBLE (-7923 5525);
FORCEADD TAP..1
R 2
(-7925 5575);
FORCEPROP 3 LASTPIN (-7875 5575) SIG_NAME M_C_CPU0_SA_CA<3>
J 0
(-7865 5585);
DISPLAY 0.659574 (-7865 5585);
PAINT MONO (-7865 5585);
DISPLAY INVISIBLE (-7865 5585);
FORCEPROP 1 LASTPIN (-7875 5575) BN 3
J 2
(-7863 5583);
DISPLAY 0.489362 (-7863 5583);
PAINT GREEN (-7863 5583);
FORCEPROP 2 LAST CDS_LIB mstr_standard
J 0
(-7925 5575);
DISPLAY 0.723404 (-7925 5575);
PAINT MONO (-7925 5575);
DISPLAY INVISIBLE (-7925 5575);
FORCEPROP 1 LAST BODY_TYPE PLUMBING
J 2
(-7925 5625);
DISPLAY 0.872340 (-7925 5625);
PAINT GREEN (-7925 5625);
DISPLAY INVISIBLE (-7925 5625);
FORCEPROP 1 LAST HDL_TAP TRUE
J 2
(-8250 5450);
DISPLAY 0.872340 (-8250 5450);
DISPLAY INVISIBLE (-8250 5450);
FORCEPROP 1 LAST PATH I269
J 2
(-7923 5575);
DISPLAY 0.872340 (-7923 5575);
PAINT GREEN (-7923 5575);
DISPLAY INVISIBLE (-7923 5575);
FORCEADD TAP..1
R 2
(-7925 5675);
FORCEPROP 3 LASTPIN (-7875 5675) SIG_NAME M_C_CPU0_SA_CA<5>
J 0
(-7865 5685);
DISPLAY 0.659574 (-7865 5685);
PAINT MONO (-7865 5685);
DISPLAY INVISIBLE (-7865 5685);
FORCEPROP 1 LASTPIN (-7875 5675) BN 5
J 2
(-7863 5683);
DISPLAY 0.489362 (-7863 5683);
PAINT GREEN (-7863 5683);
FORCEPROP 2 LAST CDS_LIB mstr_standard
J 0
(-7925 5675);
DISPLAY 0.723404 (-7925 5675);
PAINT MONO (-7925 5675);
DISPLAY INVISIBLE (-7925 5675);
FORCEPROP 1 LAST BODY_TYPE PLUMBING
J 2
(-7925 5725);
DISPLAY 0.872340 (-7925 5725);
PAINT GREEN (-7925 5725);
DISPLAY INVISIBLE (-7925 5725);
FORCEPROP 1 LAST HDL_TAP TRUE
J 2
(-8250 5550);
DISPLAY 0.872340 (-8250 5550);
DISPLAY INVISIBLE (-8250 5550);
FORCEPROP 1 LAST PATH I270
J 2
(-7923 5675);
DISPLAY 0.872340 (-7923 5675);
PAINT GREEN (-7923 5675);
DISPLAY INVISIBLE (-7923 5675);
FORCEADD TAP..1
R 2
(-7925 5625);
FORCEPROP 3 LASTPIN (-7875 5625) SIG_NAME M_C_CPU0_SA_CA<4>
J 0
(-7865 5635);
DISPLAY 0.659574 (-7865 5635);
PAINT MONO (-7865 5635);
DISPLAY INVISIBLE (-7865 5635);
FORCEPROP 1 LASTPIN (-7875 5625) BN 4
J 2
(-7863 5633);
DISPLAY 0.489362 (-7863 5633);
PAINT GREEN (-7863 5633);
FORCEPROP 2 LAST CDS_LIB mstr_standard
J 0
(-7925 5625);
DISPLAY 0.723404 (-7925 5625);
PAINT MONO (-7925 5625);
DISPLAY INVISIBLE (-7925 5625);
FORCEPROP 1 LAST BODY_TYPE PLUMBING
J 2
(-7925 5675);
DISPLAY 0.872340 (-7925 5675);
PAINT GREEN (-7925 5675);
DISPLAY INVISIBLE (-7925 5675);
FORCEPROP 1 LAST HDL_TAP TRUE
J 2
(-8250 5500);
DISPLAY 0.872340 (-8250 5500);
DISPLAY INVISIBLE (-8250 5500);
FORCEPROP 1 LAST PATH I271
J 2
(-7923 5625);
DISPLAY 0.872340 (-7923 5625);
PAINT GREEN (-7923 5625);
DISPLAY INVISIBLE (-7923 5625);
FORCEADD TAP..1
R 2
(-7925 5725);
FORCEPROP 3 LASTPIN (-7875 5725) SIG_NAME M_C_CPU0_SA_CA<6>
J 0
(-7865 5735);
DISPLAY 0.659574 (-7865 5735);
PAINT MONO (-7865 5735);
DISPLAY INVISIBLE (-7865 5735);
FORCEPROP 1 LASTPIN (-7875 5725) BN 6
J 2
(-7863 5733);
DISPLAY 0.489362 (-7863 5733);
PAINT GREEN (-7863 5733);
FORCEPROP 2 LAST CDS_LIB mstr_standard
J 0
(-7925 5725);
DISPLAY 0.723404 (-7925 5725);
PAINT MONO (-7925 5725);
DISPLAY INVISIBLE (-7925 5725);
FORCEPROP 1 LAST BODY_TYPE PLUMBING
J 2
(-7925 5775);
DISPLAY 0.872340 (-7925 5775);
PAINT GREEN (-7925 5775);
DISPLAY INVISIBLE (-7925 5775);
FORCEPROP 1 LAST HDL_TAP TRUE
J 2
(-8250 5600);
DISPLAY 0.872340 (-8250 5600);
DISPLAY INVISIBLE (-8250 5600);
FORCEPROP 1 LAST PATH I272
J 2
(-7923 5725);
DISPLAY 0.872340 (-7923 5725);
PAINT GREEN (-7923 5725);
DISPLAY INVISIBLE (-7923 5725);
FORCEADD TAP..1
(-6225 5325);
FORCEPROP 3 LASTPIN (-6275 5325) SIG_NAME M_C_CPU0_SA_DQ<23>
J 0
(-6265 5335);
DISPLAY 0.659574 (-6265 5335);
PAINT MONO (-6265 5335);
DISPLAY INVISIBLE (-6265 5335);
FORCEPROP 1 LASTPIN (-6275 5325) BN 23
J 0
(-6287 5333);
DISPLAY 0.489362 (-6287 5333);
PAINT GREEN (-6287 5333);
FORCEPROP 2 LAST CDS_LIB mstr_standard
J 0
(-6225 5325);
DISPLAY 0.723404 (-6225 5325);
PAINT MONO (-6225 5325);
DISPLAY INVISIBLE (-6225 5325);
FORCEPROP 1 LAST BODY_TYPE PLUMBING
J 0
(-6225 5375);
DISPLAY 0.872340 (-6225 5375);
PAINT GREEN (-6225 5375);
DISPLAY INVISIBLE (-6225 5375);
FORCEPROP 1 LAST HDL_TAP TRUE
J 0
(-5900 5200);
DISPLAY 0.872340 (-5900 5200);
DISPLAY INVISIBLE (-5900 5200);
FORCEPROP 1 LAST PATH I273
J 0
(-6227 5325);
DISPLAY 0.872340 (-6227 5325);
PAINT GREEN (-6227 5325);
DISPLAY INVISIBLE (-6227 5325);
FORCEADD TAP..1
(-6225 5225);
FORCEPROP 3 LASTPIN (-6275 5225) SIG_NAME M_C_CPU0_SA_DQ<21>
J 0
(-6265 5235);
DISPLAY 0.659574 (-6265 5235);
PAINT MONO (-6265 5235);
DISPLAY INVISIBLE (-6265 5235);
FORCEPROP 1 LASTPIN (-6275 5225) BN 21
J 0
(-6287 5233);
DISPLAY 0.489362 (-6287 5233);
PAINT GREEN (-6287 5233);
FORCEPROP 2 LAST CDS_LIB mstr_standard
J 0
(-6225 5225);
DISPLAY 0.723404 (-6225 5225);
PAINT MONO (-6225 5225);
DISPLAY INVISIBLE (-6225 5225);
FORCEPROP 1 LAST BODY_TYPE PLUMBING
J 0
(-6225 5275);
DISPLAY 0.872340 (-6225 5275);
PAINT GREEN (-6225 5275);
DISPLAY INVISIBLE (-6225 5275);
FORCEPROP 1 LAST HDL_TAP TRUE
J 0
(-5900 5100);
DISPLAY 0.872340 (-5900 5100);
DISPLAY INVISIBLE (-5900 5100);
FORCEPROP 1 LAST PATH I274
J 0
(-6227 5225);
DISPLAY 0.872340 (-6227 5225);
PAINT GREEN (-6227 5225);
DISPLAY INVISIBLE (-6227 5225);
FORCEADD TAP..1
(-6225 5275);
FORCEPROP 3 LASTPIN (-6275 5275) SIG_NAME M_C_CPU0_SA_DQ<22>
J 0
(-6265 5285);
DISPLAY 0.659574 (-6265 5285);
PAINT MONO (-6265 5285);
DISPLAY INVISIBLE (-6265 5285);
FORCEPROP 1 LASTPIN (-6275 5275) BN 22
J 0
(-6287 5283);
DISPLAY 0.489362 (-6287 5283);
PAINT GREEN (-6287 5283);
FORCEPROP 2 LAST CDS_LIB mstr_standard
J 0
(-6225 5275);
DISPLAY 0.723404 (-6225 5275);
PAINT MONO (-6225 5275);
DISPLAY INVISIBLE (-6225 5275);
FORCEPROP 1 LAST BODY_TYPE PLUMBING
J 0
(-6225 5325);
DISPLAY 0.872340 (-6225 5325);
PAINT GREEN (-6225 5325);
DISPLAY INVISIBLE (-6225 5325);
FORCEPROP 1 LAST HDL_TAP TRUE
J 0
(-5900 5150);
DISPLAY 0.872340 (-5900 5150);
DISPLAY INVISIBLE (-5900 5150);
FORCEPROP 1 LAST PATH I275
J 0
(-6227 5275);
DISPLAY 0.872340 (-6227 5275);
PAINT GREEN (-6227 5275);
DISPLAY INVISIBLE (-6227 5275);
FORCEADD TAP..1
(-6225 5375);
FORCEPROP 3 LASTPIN (-6275 5375) SIG_NAME M_C_CPU0_SA_DQ<24>
J 0
(-6265 5385);
DISPLAY 0.659574 (-6265 5385);
PAINT MONO (-6265 5385);
DISPLAY INVISIBLE (-6265 5385);
FORCEPROP 1 LASTPIN (-6275 5375) BN 24
J 0
(-6287 5383);
DISPLAY 0.489362 (-6287 5383);
PAINT GREEN (-6287 5383);
FORCEPROP 2 LAST CDS_LIB mstr_standard
J 0
(-6225 5375);
DISPLAY 0.723404 (-6225 5375);
PAINT MONO (-6225 5375);
DISPLAY INVISIBLE (-6225 5375);
FORCEPROP 1 LAST BODY_TYPE PLUMBING
J 0
(-6225 5425);
DISPLAY 0.872340 (-6225 5425);
PAINT GREEN (-6225 5425);
DISPLAY INVISIBLE (-6225 5425);
FORCEPROP 1 LAST HDL_TAP TRUE
J 0
(-5900 5250);
DISPLAY 0.872340 (-5900 5250);
DISPLAY INVISIBLE (-5900 5250);
FORCEPROP 1 LAST PATH I276
J 0
(-6227 5375);
DISPLAY 0.872340 (-6227 5375);
PAINT GREEN (-6227 5375);
DISPLAY INVISIBLE (-6227 5375);
FORCEADD TAP..1
(-6225 5425);
FORCEPROP 3 LASTPIN (-6275 5425) SIG_NAME M_C_CPU0_SA_DQ<25>
J 0
(-6265 5435);
DISPLAY 0.659574 (-6265 5435);
PAINT MONO (-6265 5435);
DISPLAY INVISIBLE (-6265 5435);
FORCEPROP 1 LASTPIN (-6275 5425) BN 25
J 0
(-6287 5433);
DISPLAY 0.489362 (-6287 5433);
PAINT GREEN (-6287 5433);
FORCEPROP 2 LAST CDS_LIB mstr_standard
J 0
(-6225 5425);
DISPLAY 0.723404 (-6225 5425);
PAINT MONO (-6225 5425);
DISPLAY INVISIBLE (-6225 5425);
FORCEPROP 1 LAST BODY_TYPE PLUMBING
J 0
(-6225 5475);
DISPLAY 0.872340 (-6225 5475);
PAINT GREEN (-6225 5475);
DISPLAY INVISIBLE (-6225 5475);
FORCEPROP 1 LAST HDL_TAP TRUE
J 0
(-5900 5300);
DISPLAY 0.872340 (-5900 5300);
DISPLAY INVISIBLE (-5900 5300);
FORCEPROP 1 LAST PATH I277
J 0
(-6227 5425);
DISPLAY 0.872340 (-6227 5425);
PAINT GREEN (-6227 5425);
DISPLAY INVISIBLE (-6227 5425);
FORCEADD TAP..1
(-6225 5475);
FORCEPROP 3 LASTPIN (-6275 5475) SIG_NAME M_C_CPU0_SA_DQ<26>
J 0
(-6265 5485);
DISPLAY 0.659574 (-6265 5485);
PAINT MONO (-6265 5485);
DISPLAY INVISIBLE (-6265 5485);
FORCEPROP 1 LASTPIN (-6275 5475) BN 26
J 0
(-6287 5483);
DISPLAY 0.489362 (-6287 5483);
PAINT GREEN (-6287 5483);
FORCEPROP 2 LAST CDS_LIB mstr_standard
J 0
(-6225 5475);
DISPLAY 0.723404 (-6225 5475);
PAINT MONO (-6225 5475);
DISPLAY INVISIBLE (-6225 5475);
FORCEPROP 1 LAST BODY_TYPE PLUMBING
J 0
(-6225 5525);
DISPLAY 0.872340 (-6225 5525);
PAINT GREEN (-6225 5525);
DISPLAY INVISIBLE (-6225 5525);
FORCEPROP 1 LAST HDL_TAP TRUE
J 0
(-5900 5350);
DISPLAY 0.872340 (-5900 5350);
DISPLAY INVISIBLE (-5900 5350);
FORCEPROP 1 LAST PATH I278
J 0
(-6227 5475);
DISPLAY 0.872340 (-6227 5475);
PAINT GREEN (-6227 5475);
DISPLAY INVISIBLE (-6227 5475);
FORCEADD TAP..1
(-6225 5725);
FORCEPROP 3 LASTPIN (-6275 5725) SIG_NAME M_C_CPU0_SA_DQ<31>
J 0
(-6265 5735);
DISPLAY 0.659574 (-6265 5735);
PAINT MONO (-6265 5735);
DISPLAY INVISIBLE (-6265 5735);
FORCEPROP 1 LASTPIN (-6275 5725) BN 31
J 0
(-6287 5733);
DISPLAY 0.489362 (-6287 5733);
PAINT GREEN (-6287 5733);
FORCEPROP 2 LAST CDS_LIB mstr_standard
J 0
(-6225 5725);
DISPLAY 0.723404 (-6225 5725);
PAINT MONO (-6225 5725);
DISPLAY INVISIBLE (-6225 5725);
FORCEPROP 1 LAST BODY_TYPE PLUMBING
J 0
(-6225 5775);
DISPLAY 0.872340 (-6225 5775);
PAINT GREEN (-6225 5775);
DISPLAY INVISIBLE (-6225 5775);
FORCEPROP 1 LAST HDL_TAP TRUE
J 0
(-5900 5600);
DISPLAY 0.872340 (-5900 5600);
DISPLAY INVISIBLE (-5900 5600);
FORCEPROP 1 LAST PATH I279
J 0
(-6227 5725);
DISPLAY 0.872340 (-6227 5725);
PAINT GREEN (-6227 5725);
DISPLAY INVISIBLE (-6227 5725);
FORCEADD TAP..1
(-6225 5525);
FORCEPROP 3 LASTPIN (-6275 5525) SIG_NAME M_C_CPU0_SA_DQ<27>
J 0
(-6265 5535);
DISPLAY 0.659574 (-6265 5535);
PAINT MONO (-6265 5535);
DISPLAY INVISIBLE (-6265 5535);
FORCEPROP 1 LASTPIN (-6275 5525) BN 27
J 0
(-6287 5533);
DISPLAY 0.489362 (-6287 5533);
PAINT GREEN (-6287 5533);
FORCEPROP 2 LAST CDS_LIB mstr_standard
J 0
(-6225 5525);
DISPLAY 0.723404 (-6225 5525);
PAINT MONO (-6225 5525);
DISPLAY INVISIBLE (-6225 5525);
FORCEPROP 1 LAST BODY_TYPE PLUMBING
J 0
(-6225 5575);
DISPLAY 0.872340 (-6225 5575);
PAINT GREEN (-6225 5575);
DISPLAY INVISIBLE (-6225 5575);
FORCEPROP 1 LAST HDL_TAP TRUE
J 0
(-5900 5400);
DISPLAY 0.872340 (-5900 5400);
DISPLAY INVISIBLE (-5900 5400);
FORCEPROP 1 LAST PATH I280
J 0
(-6227 5525);
DISPLAY 0.872340 (-6227 5525);
PAINT GREEN (-6227 5525);
DISPLAY INVISIBLE (-6227 5525);
FORCEADD TAP..1
(-6225 5575);
FORCEPROP 3 LASTPIN (-6275 5575) SIG_NAME M_C_CPU0_SA_DQ<28>
J 0
(-6265 5585);
DISPLAY 0.659574 (-6265 5585);
PAINT MONO (-6265 5585);
DISPLAY INVISIBLE (-6265 5585);
FORCEPROP 1 LASTPIN (-6275 5575) BN 28
J 0
(-6287 5583);
DISPLAY 0.489362 (-6287 5583);
PAINT GREEN (-6287 5583);
FORCEPROP 2 LAST CDS_LIB mstr_standard
J 0
(-6225 5575);
DISPLAY 0.723404 (-6225 5575);
PAINT MONO (-6225 5575);
DISPLAY INVISIBLE (-6225 5575);
FORCEPROP 1 LAST BODY_TYPE PLUMBING
J 0
(-6225 5625);
DISPLAY 0.872340 (-6225 5625);
PAINT GREEN (-6225 5625);
DISPLAY INVISIBLE (-6225 5625);
FORCEPROP 1 LAST HDL_TAP TRUE
J 0
(-5900 5450);
DISPLAY 0.872340 (-5900 5450);
DISPLAY INVISIBLE (-5900 5450);
FORCEPROP 1 LAST PATH I281
J 0
(-6227 5575);
DISPLAY 0.872340 (-6227 5575);
PAINT GREEN (-6227 5575);
DISPLAY INVISIBLE (-6227 5575);
FORCEADD TAP..1
(-6225 5675);
FORCEPROP 3 LASTPIN (-6275 5675) SIG_NAME M_C_CPU0_SA_DQ<30>
J 0
(-6265 5685);
DISPLAY 0.659574 (-6265 5685);
PAINT MONO (-6265 5685);
DISPLAY INVISIBLE (-6265 5685);
FORCEPROP 1 LASTPIN (-6275 5675) BN 30
J 0
(-6287 5683);
DISPLAY 0.489362 (-6287 5683);
PAINT GREEN (-6287 5683);
FORCEPROP 2 LAST CDS_LIB mstr_standard
J 0
(-6225 5675);
DISPLAY 0.723404 (-6225 5675);
PAINT MONO (-6225 5675);
DISPLAY INVISIBLE (-6225 5675);
FORCEPROP 1 LAST BODY_TYPE PLUMBING
J 0
(-6225 5725);
DISPLAY 0.872340 (-6225 5725);
PAINT GREEN (-6225 5725);
DISPLAY INVISIBLE (-6225 5725);
FORCEPROP 1 LAST HDL_TAP TRUE
J 0
(-5900 5550);
DISPLAY 0.872340 (-5900 5550);
DISPLAY INVISIBLE (-5900 5550);
FORCEPROP 1 LAST PATH I282
J 0
(-6227 5675);
DISPLAY 0.872340 (-6227 5675);
PAINT GREEN (-6227 5675);
DISPLAY INVISIBLE (-6227 5675);
FORCEADD TAP..1
(-6225 5625);
FORCEPROP 3 LASTPIN (-6275 5625) SIG_NAME M_C_CPU0_SA_DQ<29>
J 0
(-6265 5635);
DISPLAY 0.659574 (-6265 5635);
PAINT MONO (-6265 5635);
DISPLAY INVISIBLE (-6265 5635);
FORCEPROP 1 LASTPIN (-6275 5625) BN 29
J 0
(-6287 5633);
DISPLAY 0.489362 (-6287 5633);
PAINT GREEN (-6287 5633);
FORCEPROP 2 LAST CDS_LIB mstr_standard
J 0
(-6225 5625);
DISPLAY 0.723404 (-6225 5625);
PAINT MONO (-6225 5625);
DISPLAY INVISIBLE (-6225 5625);
FORCEPROP 1 LAST BODY_TYPE PLUMBING
J 0
(-6225 5675);
DISPLAY 0.872340 (-6225 5675);
PAINT GREEN (-6225 5675);
DISPLAY INVISIBLE (-6225 5675);
FORCEPROP 1 LAST HDL_TAP TRUE
J 0
(-5900 5500);
DISPLAY 0.872340 (-5900 5500);
DISPLAY INVISIBLE (-5900 5500);
FORCEPROP 1 LAST PATH I283
J 0
(-6227 5625);
DISPLAY 0.872340 (-6227 5625);
PAINT GREEN (-6227 5625);
DISPLAY INVISIBLE (-6227 5625);
FORCEADD OFFPAGE..3
(-5675 5775);
FORCEPROP 2 LAST $XR0 12 
J 0
(-5461 5775);
DISPLAY 0.638298 (-5461 5775);
PAINT MONO (-5461 5775);
FORCEPROP 2 LAST PATH I284
J 0
(-5450 5825);
DISPLAY 0.808511 (-5450 5825);
DISPLAY INVISIBLE (-5450 5825);
FORCEPROP 1 LAST COMMENT_BODY TRUE
J 0
(-5725 5675);
DISPLAY 0.872340 (-5725 5675);
PAINT GREEN (-5725 5675);
DISPLAY INVISIBLE (-5725 5675);
FORCEPROP 1 LAST OFFPAGE TRUE
J 0
(-5350 5650);
DISPLAY 0.872340 (-5350 5650);
PAINT GREEN (-5350 5650);
DISPLAY INVISIBLE (-5350 5650);
FORCEPROP 2 LAST CDS_LIB mstr_standard
J 0
(-5675 5775);
DISPLAY 0.723404 (-5675 5775);
PAINT MONO (-5675 5775);
DISPLAY INVISIBLE (-5675 5775);
FORCEADD GND..1
(-6625 1350);
FORCEPROP 3 LASTPIN (-6625 1400) SIG_NAME GND\g
J 0
(-6615 1410);
DISPLAY 0.659574 (-6615 1410);
PAINT MONO (-6615 1410);
DISPLAY INVISIBLE (-6615 1410);
FORCEPROP 2 LAST BOM_COST MEM
J 0
(-6725 1425);
DISPLAY 0.808511 (-6725 1425);
DISPLAY INVISIBLE (-6725 1425);
FORCEPROP 2 LAST CDS_LIB mstr_symbols
J 0
(-6625 1350);
DISPLAY 0.808511 (-6625 1350);
DISPLAY INVISIBLE (-6625 1350);
FORCEPROP 1 LAST SIZE 1B
J 0
(-6550 1300);
DISPLAY 0.851064 (-6550 1300);
PAINT GREEN (-6550 1300);
DISPLAY INVISIBLE (-6550 1300);
FORCEPROP 1 LAST BODY_TYPE PLUMBING
J 0
(-6670 1307);
DISPLAY 0.340426 (-6670 1307);
PAINT GREEN (-6670 1307);
DISPLAY INVISIBLE (-6670 1307);
FORCEPROP 1 LAST PATH I332
J 0
(-6550 1350);
DISPLAY 0.872340 (-6550 1350);
PAINT GREEN (-6550 1350);
DISPLAY INVISIBLE (-6550 1350);
FORCEPROP 1 LAST VOLTAGE 0.0
J 0
(-6670 1307);
DISPLAY 0.723404 (-6670 1307);
PAINT SKYBLUE (-6670 1307);
DISPLAY INVISIBLE (-6670 1307);
FORCEPROP 1 LAST HDL_POWER GND
J 0
(-6625 1500);
DISPLAY 0.851064 (-6625 1500);
PAINT GREEN (-6625 1500);
DISPLAY INVISIBLE (-6625 1500);
FORCEADD OFFPAGE..5
(-7400 1750);
FORCEPROP 2 LAST $XR0 87 
J 0
(-7654 1750);
DISPLAY 0.638298 (-7654 1750);
PAINT MONO (-7654 1750);
FORCEPROP 2 LAST PATH I333
J 0
(-7350 1825);
DISPLAY 0.808511 (-7350 1825);
DISPLAY INVISIBLE (-7350 1825);
FORCEPROP 1 LAST COMMENT_BODY TRUE
J 0
(-7300 1675);
DISPLAY 0.872340 (-7300 1675);
PAINT GREEN (-7300 1675);
DISPLAY INVISIBLE (-7300 1675);
FORCEPROP 1 LAST OFFPAGE TRUE
J 0
(-7075 1625);
DISPLAY 0.872340 (-7075 1625);
PAINT GREEN (-7075 1625);
DISPLAY INVISIBLE (-7075 1625);
FORCEPROP 2 LAST BOM_COST MEM
J 0
(-7475 1825);
DISPLAY 0.808511 (-7475 1825);
DISPLAY INVISIBLE (-7475 1825);
FORCEPROP 2 LAST CDS_LIB mstr_standard
J 0
(-7400 1750);
DISPLAY 0.808511 (-7400 1750);
DISPLAY INVISIBLE (-7400 1750);
FORCEADD OFFPAGE..1
(-8525 3225);
FORCEPROP 2 LAST $XR0 87 
J 0
(-8746 3225);
DISPLAY 0.638298 (-8746 3225);
PAINT MONO (-8746 3225);
FORCEPROP 2 LAST PATH I334
J 0
(-8475 3300);
DISPLAY 0.808511 (-8475 3300);
DISPLAY INVISIBLE (-8475 3300);
FORCEPROP 1 LAST COMMENT_BODY TRUE
J 0
(-8400 3125);
DISPLAY 0.872340 (-8400 3125);
PAINT GREEN (-8400 3125);
DISPLAY INVISIBLE (-8400 3125);
FORCEPROP 1 LAST OFFPAGE TRUE
J 0
(-8200 3100);
DISPLAY 0.872340 (-8200 3100);
PAINT GREEN (-8200 3100);
DISPLAY INVISIBLE (-8200 3100);
FORCEPROP 2 LAST CDS_LIB mstr_standard
J 0
(-8525 3225);
DISPLAY 0.808511 (-8525 3225);
DISPLAY INVISIBLE (-8525 3225);
FORCEADD Q_RES..2
(-6625 1575);
FORCEPROP 1 LAST LOCATION R762
J 0
(-6580 1700);
DISPLAY 0.489362 (-6580 1700);
PAINT SKYBLUE (-6580 1700);
FORCEPROP 0 LAST $SEC 1
J 0
(-6575 1750);
DISPLAY 0.680851 (-6575 1750);
PAINT MONO (-6575 1750);
DISPLAY INVISIBLE (-6575 1750);
FORCEPROP 0 LAST CDS_SEC 1
J 0
(-6575 1750);
DISPLAY 1.021277 (-6575 1750);
DISPLAY INVISIBLE (-6575 1750);
FORCEPROP 1 LASTPIN (-6625 1675) $PN 1
J 0
(-6620 1637);
DISPLAY 0.489362 (-6620 1637);
PAINT MONO (-6620 1637);
FORCEPROP 1 LASTPIN (-6625 1475) $PN 2
J 0
(-6620 1485);
DISPLAY 0.489362 (-6620 1485);
PAINT MONO (-6620 1485);
FORCEPROP 1 LAST WATTAGE 1/16W
J 0
(-6585 1550);
DISPLAY 0.489362 (-6585 1550);
PAINT SKYBLUE (-6585 1550);
FORCEPROP 1 LAST MATERIAL CHIP
J 0
(-6585 1500);
DISPLAY 0.489362 (-6585 1500);
PAINT SKYBLUE (-6585 1500);
FORCEPROP 1 LAST TOLERANCE 1%
J 0
(-6580 1600);
DISPLAY 0.489362 (-6580 1600);
PAINT SKYBLUE (-6580 1600);
FORCEPROP 1 LAST VALUE 23.2K
J 0
(-6580 1650);
DISPLAY 0.489362 (-6580 1650);
PAINT SKYBLUE (-6580 1650);
FORCEPROP 1 LAST PART_NUMBER TMP_QCS32322FB11
J 0
(-6585 1450);
DISPLAY 0.489362 (-6585 1450);
PAINT SKYBLUE (-6585 1450);
FORCEPROP 1 LAST PACK_TYPE 0402LF
J 0
(-6585 1400);
DISPLAY 0.489362 (-6585 1400);
PAINT SKYBLUE (-6585 1400);
FORCEPROP 2 LAST CDS_LIB pure_quanta
J 0
(-6625 1575);
DISPLAY INVISIBLE (-6625 1575);
FORCEPROP 1 LAST PATH I349
J 0
(-6575 1750);
DISPLAY 0.978723 (-6575 1750);
PAINT WHITE (-6575 1750);
DISPLAY INVISIBLE (-6575 1750);
FORCEADD SCONN288_DDR506112002KQ..1
(-7075 3975);
FORCEPROP 1 LAST LOCATION J17
J 0
(-7525 6050);
DISPLAY 0.468085 (-7525 6050);
PAINT SKYBLUE (-7525 6050);
FORCEPROP 0 LAST $SEC 1
J 0
(-7525 6200);
DISPLAY 0.680851 (-7525 6200);
PAINT MONO (-7525 6200);
DISPLAY INVISIBLE (-7525 6200);
FORCEPROP 2 LAST CDS_SEC 1
J 0
(-7525 6200);
DISPLAY 1.021277 (-7525 6200);
DISPLAY INVISIBLE (-7525 6200);
FORCEPROP 0 LASTPIN (-7675 3375) $PN 62
J 2
(-7685 3385);
DISPLAY 0.680851 (-7685 3385);
PAINT MONO (-7685 3385);
FORCEPROP 0 LASTPIN (-7675 5425) $PN 66
J 2
(-7685 5435);
DISPLAY 0.680851 (-7685 5435);
PAINT MONO (-7685 5435);
FORCEPROP 0 LASTPIN (-7675 5025) $PN 76
J 2
(-7685 5035);
DISPLAY 0.680851 (-7685 5035);
PAINT MONO (-7685 5035);
FORCEPROP 0 LASTPIN (-7675 5475) $PN 211
J 2
(-7685 5485);
DISPLAY 0.680851 (-7685 5485);
PAINT MONO (-7685 5485);
FORCEPROP 0 LASTPIN (-7675 5075) $PN 221
J 2
(-7685 5085);
DISPLAY 0.680851 (-7685 5085);
PAINT MONO (-7685 5085);
FORCEPROP 0 LASTPIN (-7675 5525) $PN 68
J 2
(-7685 5535);
DISPLAY 0.680851 (-7685 5535);
PAINT MONO (-7685 5535);
FORCEPROP 0 LASTPIN (-7675 5125) $PN 78
J 2
(-7685 5135);
DISPLAY 0.680851 (-7685 5135);
PAINT MONO (-7685 5135);
FORCEPROP 0 LASTPIN (-7675 5575) $PN 213
J 2
(-7685 5585);
DISPLAY 0.680851 (-7685 5585);
PAINT MONO (-7685 5585);
FORCEPROP 0 LASTPIN (-7675 5175) $PN 223
J 2
(-7685 5185);
DISPLAY 0.680851 (-7685 5185);
PAINT MONO (-7685 5185);
FORCEPROP 0 LASTPIN (-7675 5625) $PN 70
J 2
(-7685 5635);
DISPLAY 0.680851 (-7685 5635);
PAINT MONO (-7685 5635);
FORCEPROP 0 LASTPIN (-7675 5225) $PN 80
J 2
(-7685 5235);
DISPLAY 0.680851 (-7685 5235);
PAINT MONO (-7685 5235);
FORCEPROP 0 LASTPIN (-7675 5675) $PN 215
J 2
(-7685 5685);
DISPLAY 0.680851 (-7685 5685);
PAINT MONO (-7685 5685);
FORCEPROP 0 LASTPIN (-7675 5275) $PN 225
J 2
(-7685 5285);
DISPLAY 0.680851 (-7685 5285);
PAINT MONO (-7685 5285);
FORCEPROP 0 LASTPIN (-7675 5725) $PN 72
J 2
(-7685 5735);
DISPLAY 0.680851 (-7685 5735);
PAINT MONO (-7685 5735);
FORCEPROP 0 LASTPIN (-7675 5325) $PN 82
J 2
(-7685 5335);
DISPLAY 0.680851 (-7685 5335);
PAINT MONO (-7685 5335);
FORCEPROP 0 LASTPIN (-7675 3975) $PN 51
J 2
(-7685 3985);
DISPLAY 0.680851 (-7685 3985);
PAINT MONO (-7685 3985);
FORCEPROP 0 LASTPIN (-7675 3525) $PN 96
J 2
(-7685 3535);
DISPLAY 0.680851 (-7685 3535);
PAINT MONO (-7685 3535);
FORCEPROP 0 LASTPIN (-7675 4025) $PN 53
J 2
(-7685 4035);
DISPLAY 0.680851 (-7685 4035);
PAINT MONO (-7685 4035);
FORCEPROP 0 LASTPIN (-7675 3575) $PN 98
J 2
(-7685 3585);
DISPLAY 0.680851 (-7685 3585);
PAINT MONO (-7685 3585);
FORCEPROP 0 LASTPIN (-7675 4075) $PN 196
J 2
(-7685 4085);
DISPLAY 0.680851 (-7685 4085);
PAINT MONO (-7685 4085);
FORCEPROP 0 LASTPIN (-7675 3625) $PN 241
J 2
(-7685 3635);
DISPLAY 0.680851 (-7685 3635);
PAINT MONO (-7685 3635);
FORCEPROP 0 LASTPIN (-7675 4125) $PN 198
J 2
(-7685 4135);
DISPLAY 0.680851 (-7685 4135);
PAINT MONO (-7685 4135);
FORCEPROP 0 LASTPIN (-7675 3675) $PN 243
J 2
(-7685 3685);
DISPLAY 0.680851 (-7685 3685);
PAINT MONO (-7685 3685);
FORCEPROP 0 LASTPIN (-7675 4175) $PN 58
J 2
(-7685 4185);
DISPLAY 0.680851 (-7685 4185);
PAINT MONO (-7685 4185);
FORCEPROP 0 LASTPIN (-7675 3725) $PN 89
J 2
(-7685 3735);
DISPLAY 0.680851 (-7685 3735);
PAINT MONO (-7685 3735);
FORCEPROP 0 LASTPIN (-7675 4225) $PN 60
J 2
(-7685 4235);
DISPLAY 0.680851 (-7685 4235);
PAINT MONO (-7685 4235);
FORCEPROP 0 LASTPIN (-7675 3775) $PN 91
J 2
(-7685 3785);
DISPLAY 0.680851 (-7685 3785);
PAINT MONO (-7685 3785);
FORCEPROP 0 LASTPIN (-7675 4275) $PN 203
J 2
(-7685 4285);
DISPLAY 0.680851 (-7685 4285);
PAINT MONO (-7685 4285);
FORCEPROP 0 LASTPIN (-7675 3825) $PN 234
J 2
(-7685 3835);
DISPLAY 0.680851 (-7685 3835);
PAINT MONO (-7685 3835);
FORCEPROP 0 LASTPIN (-7675 4325) $PN 205
J 2
(-7685 4335);
DISPLAY 0.680851 (-7685 4335);
PAINT MONO (-7685 4335);
FORCEPROP 0 LASTPIN (-7675 3875) $PN 236
J 2
(-7685 3885);
DISPLAY 0.680851 (-7685 3885);
PAINT MONO (-7685 3885);
FORCEPROP 0 LASTPIN (-7675 4425) $PN 218
J 2
(-7685 4435);
DISPLAY 0.680851 (-7685 4435);
PAINT MONO (-7685 4435);
FORCEPROP 0 LASTPIN (-7675 4475) $PN 217
J 2
(-7685 4485);
DISPLAY 0.680851 (-7685 4485);
PAINT MONO (-7685 4485);
FORCEPROP 0 LASTPIN (-7675 4725) $PN 64
J 2
(-7685 4735);
DISPLAY 0.680851 (-7685 4735);
PAINT MONO (-7685 4735);
FORCEPROP 0 LASTPIN (-7675 4575) $PN 84
J 2
(-7685 4585);
DISPLAY 0.680851 (-7685 4585);
PAINT MONO (-7685 4585);
FORCEPROP 0 LASTPIN (-7675 4775) $PN 209
J 2
(-7685 4785);
DISPLAY 0.680851 (-7685 4785);
PAINT MONO (-7685 4785);
FORCEPROP 0 LASTPIN (-7675 4625) $PN 229
J 2
(-7685 4635);
DISPLAY 0.680851 (-7685 4635);
PAINT MONO (-7685 4635);
FORCEPROP 0 LASTPIN (-6475 4175) $PN 7
J 0
(-6465 4185);
DISPLAY 0.680851 (-6465 4185);
PAINT MONO (-6465 4185);
FORCEPROP 0 LASTPIN (-6475 2525) $PN 100
J 0
(-6465 2535);
DISPLAY 0.680851 (-6465 2535);
PAINT MONO (-6465 2535);
FORCEPROP 0 LASTPIN (-6475 4225) $PN 9
J 0
(-6465 4235);
DISPLAY 0.680851 (-6465 4235);
PAINT MONO (-6465 4235);
FORCEPROP 0 LASTPIN (-6475 2575) $PN 102
J 0
(-6465 2585);
DISPLAY 0.680851 (-6465 2585);
PAINT MONO (-6465 2585);
FORCEPROP 0 LASTPIN (-6475 4275) $PN 152
J 0
(-6465 4285);
DISPLAY 0.680851 (-6465 4285);
PAINT MONO (-6465 4285);
FORCEPROP 0 LASTPIN (-6475 2625) $PN 245
J 0
(-6465 2635);
DISPLAY 0.680851 (-6465 2635);
PAINT MONO (-6465 2635);
FORCEPROP 0 LASTPIN (-6475 4325) $PN 154
J 0
(-6465 4335);
DISPLAY 0.680851 (-6465 4335);
PAINT MONO (-6465 4335);
FORCEPROP 0 LASTPIN (-6475 2675) $PN 247
J 0
(-6465 2685);
DISPLAY 0.680851 (-6465 2685);
PAINT MONO (-6465 2685);
FORCEPROP 0 LASTPIN (-6475 4375) $PN 14
J 0
(-6465 4385);
DISPLAY 0.680851 (-6465 4385);
PAINT MONO (-6465 4385);
FORCEPROP 0 LASTPIN (-6475 2725) $PN 107
J 0
(-6465 2735);
DISPLAY 0.680851 (-6465 2735);
PAINT MONO (-6465 2735);
FORCEPROP 0 LASTPIN (-6475 4425) $PN 16
J 0
(-6465 4435);
DISPLAY 0.680851 (-6465 4435);
PAINT MONO (-6465 4435);
FORCEPROP 0 LASTPIN (-6475 2775) $PN 109
J 0
(-6465 2785);
DISPLAY 0.680851 (-6465 2785);
PAINT MONO (-6465 2785);
FORCEPROP 0 LASTPIN (-6475 4475) $PN 159
J 0
(-6465 4485);
DISPLAY 0.680851 (-6465 4485);
PAINT MONO (-6465 4485);
FORCEPROP 0 LASTPIN (-6475 2825) $PN 252
J 0
(-6465 2835);
DISPLAY 0.680851 (-6465 2835);
PAINT MONO (-6465 2835);
FORCEPROP 0 LASTPIN (-6475 4525) $PN 161
J 0
(-6465 4535);
DISPLAY 0.680851 (-6465 4535);
PAINT MONO (-6465 4535);
FORCEPROP 0 LASTPIN (-6475 2875) $PN 254
J 0
(-6465 2885);
DISPLAY 0.680851 (-6465 2885);
PAINT MONO (-6465 2885);
FORCEPROP 0 LASTPIN (-6475 4575) $PN 18
J 0
(-6465 4585);
DISPLAY 0.680851 (-6465 4585);
PAINT MONO (-6465 4585);
FORCEPROP 0 LASTPIN (-6475 2925) $PN 111
J 0
(-6465 2935);
DISPLAY 0.680851 (-6465 2935);
PAINT MONO (-6465 2935);
FORCEPROP 0 LASTPIN (-6475 4625) $PN 20
J 0
(-6465 4635);
DISPLAY 0.680851 (-6465 4635);
PAINT MONO (-6465 4635);
FORCEPROP 0 LASTPIN (-6475 2975) $PN 113
J 0
(-6465 2985);
DISPLAY 0.680851 (-6465 2985);
PAINT MONO (-6465 2985);
FORCEPROP 0 LASTPIN (-6475 4675) $PN 163
J 0
(-6465 4685);
DISPLAY 0.680851 (-6465 4685);
PAINT MONO (-6465 4685);
FORCEPROP 0 LASTPIN (-6475 3025) $PN 256
J 0
(-6465 3035);
DISPLAY 0.680851 (-6465 3035);
PAINT MONO (-6465 3035);
FORCEPROP 0 LASTPIN (-6475 4725) $PN 165
J 0
(-6465 4735);
DISPLAY 0.680851 (-6465 4735);
PAINT MONO (-6465 4735);
FORCEPROP 0 LASTPIN (-6475 3075) $PN 258
J 0
(-6465 3085);
DISPLAY 0.680851 (-6465 3085);
PAINT MONO (-6465 3085);
FORCEPROP 0 LASTPIN (-6475 4775) $PN 25
J 0
(-6465 4785);
DISPLAY 0.680851 (-6465 4785);
PAINT MONO (-6465 4785);
FORCEPROP 0 LASTPIN (-6475 3125) $PN 118
J 0
(-6465 3135);
DISPLAY 0.680851 (-6465 3135);
PAINT MONO (-6465 3135);
FORCEPROP 0 LASTPIN (-6475 4825) $PN 27
J 0
(-6465 4835);
DISPLAY 0.680851 (-6465 4835);
PAINT MONO (-6465 4835);
FORCEPROP 0 LASTPIN (-6475 3175) $PN 120
J 0
(-6465 3185);
DISPLAY 0.680851 (-6465 3185);
PAINT MONO (-6465 3185);
FORCEPROP 0 LASTPIN (-6475 4875) $PN 170
J 0
(-6465 4885);
DISPLAY 0.680851 (-6465 4885);
PAINT MONO (-6465 4885);
FORCEPROP 0 LASTPIN (-6475 3225) $PN 263
J 0
(-6465 3235);
DISPLAY 0.680851 (-6465 3235);
PAINT MONO (-6465 3235);
FORCEPROP 0 LASTPIN (-6475 4925) $PN 172
J 0
(-6465 4935);
DISPLAY 0.680851 (-6465 4935);
PAINT MONO (-6465 4935);
FORCEPROP 0 LASTPIN (-6475 3275) $PN 265
J 0
(-6465 3285);
DISPLAY 0.680851 (-6465 3285);
PAINT MONO (-6465 3285);
FORCEPROP 0 LASTPIN (-6475 4975) $PN 29
J 0
(-6465 4985);
DISPLAY 0.680851 (-6465 4985);
PAINT MONO (-6465 4985);
FORCEPROP 0 LASTPIN (-6475 3325) $PN 122
J 0
(-6465 3335);
DISPLAY 0.680851 (-6465 3335);
PAINT MONO (-6465 3335);
FORCEPROP 0 LASTPIN (-6475 5025) $PN 31
J 0
(-6465 5035);
DISPLAY 0.680851 (-6465 5035);
PAINT MONO (-6465 5035);
FORCEPROP 0 LASTPIN (-6475 3375) $PN 124
J 0
(-6465 3385);
DISPLAY 0.680851 (-6465 3385);
PAINT MONO (-6465 3385);
FORCEPROP 0 LASTPIN (-6475 5075) $PN 174
J 0
(-6465 5085);
DISPLAY 0.680851 (-6465 5085);
PAINT MONO (-6465 5085);
FORCEPROP 0 LASTPIN (-6475 3425) $PN 267
J 0
(-6465 3435);
DISPLAY 0.680851 (-6465 3435);
PAINT MONO (-6465 3435);
FORCEPROP 0 LASTPIN (-6475 5125) $PN 176
J 0
(-6465 5135);
DISPLAY 0.680851 (-6465 5135);
PAINT MONO (-6465 5135);
FORCEPROP 0 LASTPIN (-6475 3475) $PN 269
J 0
(-6465 3485);
DISPLAY 0.680851 (-6465 3485);
PAINT MONO (-6465 3485);
FORCEPROP 0 LASTPIN (-6475 5175) $PN 36
J 0
(-6465 5185);
DISPLAY 0.680851 (-6465 5185);
PAINT MONO (-6465 5185);
FORCEPROP 0 LASTPIN (-6475 3525) $PN 129
J 0
(-6465 3535);
DISPLAY 0.680851 (-6465 3535);
PAINT MONO (-6465 3535);
FORCEPROP 0 LASTPIN (-6475 5225) $PN 38
J 0
(-6465 5235);
DISPLAY 0.680851 (-6465 5235);
PAINT MONO (-6465 5235);
FORCEPROP 0 LASTPIN (-6475 3575) $PN 131
J 0
(-6465 3585);
DISPLAY 0.680851 (-6465 3585);
PAINT MONO (-6465 3585);
FORCEPROP 0 LASTPIN (-6475 5275) $PN 181
J 0
(-6465 5285);
DISPLAY 0.680851 (-6465 5285);
PAINT MONO (-6465 5285);
FORCEPROP 0 LASTPIN (-6475 3625) $PN 274
J 0
(-6465 3635);
DISPLAY 0.680851 (-6465 3635);
PAINT MONO (-6465 3635);
FORCEPROP 0 LASTPIN (-6475 5325) $PN 183
J 0
(-6465 5335);
DISPLAY 0.680851 (-6465 5335);
PAINT MONO (-6465 5335);
FORCEPROP 0 LASTPIN (-6475 3675) $PN 276
J 0
(-6465 3685);
DISPLAY 0.680851 (-6465 3685);
PAINT MONO (-6465 3685);
FORCEPROP 0 LASTPIN (-6475 5375) $PN 40
J 0
(-6465 5385);
DISPLAY 0.680851 (-6465 5385);
PAINT MONO (-6465 5385);
FORCEPROP 0 LASTPIN (-6475 3725) $PN 133
J 0
(-6465 3735);
DISPLAY 0.680851 (-6465 3735);
PAINT MONO (-6465 3735);
FORCEPROP 0 LASTPIN (-6475 5425) $PN 42
J 0
(-6465 5435);
DISPLAY 0.680851 (-6465 5435);
PAINT MONO (-6465 5435);
FORCEPROP 0 LASTPIN (-6475 3775) $PN 135
J 0
(-6465 3785);
DISPLAY 0.680851 (-6465 3785);
PAINT MONO (-6465 3785);
FORCEPROP 0 LASTPIN (-6475 5475) $PN 185
J 0
(-6465 5485);
DISPLAY 0.680851 (-6465 5485);
PAINT MONO (-6465 5485);
FORCEPROP 0 LASTPIN (-6475 3825) $PN 278
J 0
(-6465 3835);
DISPLAY 0.680851 (-6465 3835);
PAINT MONO (-6465 3835);
FORCEPROP 0 LASTPIN (-6475 5525) $PN 187
J 0
(-6465 5535);
DISPLAY 0.680851 (-6465 5535);
PAINT MONO (-6465 5535);
FORCEPROP 0 LASTPIN (-6475 3875) $PN 280
J 0
(-6465 3885);
DISPLAY 0.680851 (-6465 3885);
PAINT MONO (-6465 3885);
FORCEPROP 0 LASTPIN (-6475 5575) $PN 47
J 0
(-6465 5585);
DISPLAY 0.680851 (-6465 5585);
PAINT MONO (-6465 5585);
FORCEPROP 0 LASTPIN (-6475 3925) $PN 140
J 0
(-6465 3935);
DISPLAY 0.680851 (-6465 3935);
PAINT MONO (-6465 3935);
FORCEPROP 0 LASTPIN (-6475 5625) $PN 49
J 0
(-6465 5635);
DISPLAY 0.680851 (-6465 5635);
PAINT MONO (-6465 5635);
FORCEPROP 0 LASTPIN (-6475 3975) $PN 142
J 0
(-6465 3985);
DISPLAY 0.680851 (-6465 3985);
PAINT MONO (-6465 3985);
FORCEPROP 0 LASTPIN (-6475 5675) $PN 192
J 0
(-6465 5685);
DISPLAY 0.680851 (-6465 5685);
PAINT MONO (-6465 5685);
FORCEPROP 0 LASTPIN (-6475 4025) $PN 285
J 0
(-6465 4035);
DISPLAY 0.680851 (-6465 4035);
PAINT MONO (-6465 4035);
FORCEPROP 0 LASTPIN (-6475 5725) $PN 194
J 0
(-6465 5735);
DISPLAY 0.680851 (-6465 5735);
PAINT MONO (-6465 5735);
FORCEPROP 0 LASTPIN (-6475 4075) $PN 287
J 0
(-6465 4085);
DISPLAY 0.680851 (-6465 4085);
PAINT MONO (-6465 4085);
FORCEPROP 0 LASTPIN (-7675 3225) $PN 148
J 2
(-7685 3235);
DISPLAY 0.680851 (-7685 3235);
PAINT MONO (-7685 3235);
FORCEPROP 0 LASTPIN (-7675 3125) $PN 4
J 2
(-7685 3135);
DISPLAY 0.680851 (-7685 3135);
PAINT MONO (-7685 3135);
FORCEPROP 0 LASTPIN (-7675 3175) $PN 5
J 2
(-7685 3185);
DISPLAY 0.680851 (-7685 3185);
PAINT MONO (-7685 3185);
FORCEPROP 0 LASTPIN (-7675 2325) $PN 86
J 2
(-7685 2335);
DISPLAY 0.680851 (-7685 2335);
PAINT MONO (-7685 2335);
FORCEPROP 0 LASTPIN (-7675 2275) $PN 87
J 2
(-7685 2285);
DISPLAY 0.680851 (-7685 2285);
PAINT MONO (-7685 2285);
FORCEPROP 0 LASTPIN (-7675 4925) $PN 74
J 2
(-7685 4935);
DISPLAY 0.680851 (-7685 4935);
PAINT MONO (-7685 4935);
FORCEPROP 0 LASTPIN (-7675 4875) $PN 227
J 2
(-7685 4885);
DISPLAY 0.680851 (-7685 4885);
PAINT MONO (-7685 4885);
FORCEPROP 0 LASTPIN (-7675 2875) $PN 147
J 2
(-7685 2885);
DISPLAY 0.680851 (-7685 2885);
PAINT MONO (-7685 2885);
FORCEPROP 0 LASTPIN (-7675 3425) $PN 207
J 2
(-7685 3435);
DISPLAY 0.680851 (-7685 3435);
PAINT MONO (-7685 3435);
FORCEPROP 0 LASTPIN (-7675 2475) $PN 2
J 2
(-7685 2485);
DISPLAY 0.680851 (-7685 2485);
PAINT MONO (-7685 2485);
FORCEPROP 0 LASTPIN (-7675 2525) $PN 144
J 2
(-7685 2535);
DISPLAY 0.680851 (-7685 2535);
PAINT MONO (-7685 2535);
FORCEPROP 0 LASTPIN (-7675 2575) $PN 149
J 2
(-7685 2585);
DISPLAY 0.680851 (-7685 2585);
PAINT MONO (-7685 2585);
FORCEPROP 0 LASTPIN (-7675 2625) $PN 150
J 2
(-7685 2635);
DISPLAY 0.680851 (-7685 2635);
PAINT MONO (-7685 2635);
FORCEPROP 0 LASTPIN (-7675 2675) $PN 220
J 2
(-7685 2685);
DISPLAY 0.680851 (-7685 2685);
PAINT MONO (-7685 2685);
FORCEPROP 0 LASTPIN (-7675 2725) $PN 231
J 2
(-7685 2735);
DISPLAY 0.680851 (-7685 2735);
PAINT MONO (-7685 2735);
FORCEPROP 0 LASTPIN (-7675 2775) $PN 232
J 2
(-7685 2785);
DISPLAY 0.680851 (-7685 2785);
PAINT MONO (-7685 2785);
FORCEPROP 0 LASTPIN (-7675 3275) $PN 3
J 2
(-7685 3285);
DISPLAY 0.680851 (-7685 3285);
PAINT MONO (-7685 3285);
FORCEPROP 2 LAST VALUE SCONN288_DDR506112002KQ
J 0
(-7525 6100);
DISPLAY 0.489362 (-7525 6100);
PAINT SKYBLUE (-7525 6100);
FORCEPROP 2 LAST PART_TYPE SMLF
J 0
(-7525 6150);
DISPLAY 1.021277 (-7525 6150);
FORCEPROP 1 LAST MATERIAL IO
J 0
(-7525 5900);
DISPLAY 0.468085 (-7525 5900);
PAINT SKYBLUE (-7525 5900);
FORCEPROP 1 LAST PART_NUMBER DFHST8FS479
J 0
(-7525 5975);
DISPLAY 0.468085 (-7525 5975);
PAINT SKYBLUE (-7525 5975);
FORCEPROP 1 LAST CDS_LMAN_SYM_OUTLINE -450,1900,450,-1850
J 0
(-7075 3975);
DISPLAY 0.468085 (-7075 3975);
PAINT GREEN (-7075 3975);
DISPLAY INVISIBLE (-7075 3975);
FORCEPROP 1 LAST PATH I350
J 0
(-7075 3975);
DISPLAY 0.723404 (-7075 3975);
PAINT GREEN (-7075 3975);
DISPLAY INVISIBLE (-7075 3975);
FORCEPROP 1 LAST NEEDS_NO_SIZE TRUE
J 0
(-7075 3975);
DISPLAY 0.723404 (-7075 3975);
PAINT GREEN (-7075 3975);
DISPLAY INVISIBLE (-7075 3975);
FORCEPROP 2 LAST CDS_LIB pure_quanta
J 0
(-7075 3975);
DISPLAY INVISIBLE (-7075 3975);
FORCEADD SCONN288_DDR506112002KQ..3
(-1400 4050);
FORCEPROP 1 LAST LOCATION J17
J 0
(-1850 6025);
DISPLAY 0.468085 (-1850 6025);
PAINT SKYBLUE (-1850 6025);
FORCEPROP 0 LAST $SEC 3
J 0
(-1850 6175);
DISPLAY 0.680851 (-1850 6175);
PAINT MONO (-1850 6175);
DISPLAY INVISIBLE (-1850 6175);
FORCEPROP 2 LAST CDS_SEC 3
J 0
(-1850 6175);
DISPLAY 1.021277 (-1850 6175);
DISPLAY INVISIBLE (-1850 6175);
FORCEPROP 0 LASTPIN (-800 2450) $PN G1
J 0
(-790 2460);
DISPLAY 0.680851 (-790 2460);
PAINT MONO (-790 2460);
FORCEPROP 0 LASTPIN (-800 2400) $PN G2
J 0
(-790 2410);
DISPLAY 0.680851 (-790 2410);
PAINT MONO (-790 2410);
FORCEPROP 0 LASTPIN (-800 2350) $PN G3
J 0
(-790 2360);
DISPLAY 0.680851 (-790 2360);
PAINT MONO (-790 2360);
FORCEPROP 0 LASTPIN (-2000 5600) $PN 1
J 2
(-2010 5610);
DISPLAY 0.680851 (-2010 5610);
PAINT MONO (-2010 5610);
FORCEPROP 0 LASTPIN (-2000 5650) $PN 145
J 2
(-2010 5660);
DISPLAY 0.680851 (-2010 5660);
PAINT MONO (-2010 5660);
FORCEPROP 0 LASTPIN (-2000 5700) $PN 146
J 2
(-2010 5710);
DISPLAY 0.680851 (-2010 5710);
PAINT MONO (-2010 5710);
FORCEPROP 0 LASTPIN (-800 2550) $PN 6
J 0
(-790 2560);
DISPLAY 0.680851 (-790 2560);
PAINT MONO (-790 2560);
FORCEPROP 0 LASTPIN (-800 2600) $PN 8
J 0
(-790 2610);
DISPLAY 0.680851 (-790 2610);
PAINT MONO (-790 2610);
FORCEPROP 0 LASTPIN (-800 2650) $PN 10
J 0
(-790 2660);
DISPLAY 0.680851 (-790 2660);
PAINT MONO (-790 2660);
FORCEPROP 0 LASTPIN (-800 2700) $PN 13
J 0
(-790 2710);
DISPLAY 0.680851 (-790 2710);
PAINT MONO (-790 2710);
FORCEPROP 0 LASTPIN (-800 2750) $PN 15
J 0
(-790 2760);
DISPLAY 0.680851 (-790 2760);
PAINT MONO (-790 2760);
FORCEPROP 0 LASTPIN (-800 2800) $PN 17
J 0
(-790 2810);
DISPLAY 0.680851 (-790 2810);
PAINT MONO (-790 2810);
FORCEPROP 0 LASTPIN (-800 2850) $PN 19
J 0
(-790 2860);
DISPLAY 0.680851 (-790 2860);
PAINT MONO (-790 2860);
FORCEPROP 0 LASTPIN (-800 2900) $PN 21
J 0
(-790 2910);
DISPLAY 0.680851 (-790 2910);
PAINT MONO (-790 2910);
FORCEPROP 0 LASTPIN (-800 2950) $PN 24
J 0
(-790 2960);
DISPLAY 0.680851 (-790 2960);
PAINT MONO (-790 2960);
FORCEPROP 0 LASTPIN (-800 3000) $PN 26
J 0
(-790 3010);
DISPLAY 0.680851 (-790 3010);
PAINT MONO (-790 3010);
FORCEPROP 0 LASTPIN (-800 3050) $PN 28
J 0
(-790 3060);
DISPLAY 0.680851 (-790 3060);
PAINT MONO (-790 3060);
FORCEPROP 0 LASTPIN (-800 3100) $PN 30
J 0
(-790 3110);
DISPLAY 0.680851 (-790 3110);
PAINT MONO (-790 3110);
FORCEPROP 0 LASTPIN (-800 3150) $PN 32
J 0
(-790 3160);
DISPLAY 0.680851 (-790 3160);
PAINT MONO (-790 3160);
FORCEPROP 0 LASTPIN (-800 3200) $PN 35
J 0
(-790 3210);
DISPLAY 0.680851 (-790 3210);
PAINT MONO (-790 3210);
FORCEPROP 0 LASTPIN (-800 3250) $PN 37
J 0
(-790 3260);
DISPLAY 0.680851 (-790 3260);
PAINT MONO (-790 3260);
FORCEPROP 0 LASTPIN (-800 3300) $PN 39
J 0
(-790 3310);
DISPLAY 0.680851 (-790 3310);
PAINT MONO (-790 3310);
FORCEPROP 0 LASTPIN (-800 3350) $PN 41
J 0
(-790 3360);
DISPLAY 0.680851 (-790 3360);
PAINT MONO (-790 3360);
FORCEPROP 0 LASTPIN (-800 3400) $PN 43
J 0
(-790 3410);
DISPLAY 0.680851 (-790 3410);
PAINT MONO (-790 3410);
FORCEPROP 0 LASTPIN (-800 3450) $PN 46
J 0
(-790 3460);
DISPLAY 0.680851 (-790 3460);
PAINT MONO (-790 3460);
FORCEPROP 0 LASTPIN (-800 3500) $PN 48
J 0
(-790 3510);
DISPLAY 0.680851 (-790 3510);
PAINT MONO (-790 3510);
FORCEPROP 0 LASTPIN (-800 3550) $PN 50
J 0
(-790 3560);
DISPLAY 0.680851 (-790 3560);
PAINT MONO (-790 3560);
FORCEPROP 0 LASTPIN (-800 3600) $PN 52
J 0
(-790 3610);
DISPLAY 0.680851 (-790 3610);
PAINT MONO (-790 3610);
FORCEPROP 0 LASTPIN (-800 3650) $PN 54
J 0
(-790 3660);
DISPLAY 0.680851 (-790 3660);
PAINT MONO (-790 3660);
FORCEPROP 0 LASTPIN (-800 3700) $PN 57
J 0
(-790 3710);
DISPLAY 0.680851 (-790 3710);
PAINT MONO (-790 3710);
FORCEPROP 0 LASTPIN (-800 3750) $PN 59
J 0
(-790 3760);
DISPLAY 0.680851 (-790 3760);
PAINT MONO (-790 3760);
FORCEPROP 0 LASTPIN (-800 3800) $PN 61
J 0
(-790 3810);
DISPLAY 0.680851 (-790 3810);
PAINT MONO (-790 3810);
FORCEPROP 0 LASTPIN (-800 3850) $PN 63
J 0
(-790 3860);
DISPLAY 0.680851 (-790 3860);
PAINT MONO (-790 3860);
FORCEPROP 0 LASTPIN (-800 3900) $PN 65
J 0
(-790 3910);
DISPLAY 0.680851 (-790 3910);
PAINT MONO (-790 3910);
FORCEPROP 0 LASTPIN (-800 3950) $PN 67
J 0
(-790 3960);
DISPLAY 0.680851 (-790 3960);
PAINT MONO (-790 3960);
FORCEPROP 0 LASTPIN (-800 4000) $PN 69
J 0
(-790 4010);
DISPLAY 0.680851 (-790 4010);
PAINT MONO (-790 4010);
FORCEPROP 0 LASTPIN (-800 4050) $PN 71
J 0
(-790 4060);
DISPLAY 0.680851 (-790 4060);
PAINT MONO (-790 4060);
FORCEPROP 0 LASTPIN (-800 4100) $PN 73
J 0
(-790 4110);
DISPLAY 0.680851 (-790 4110);
PAINT MONO (-790 4110);
FORCEPROP 0 LASTPIN (-800 4150) $PN 75
J 0
(-790 4160);
DISPLAY 0.680851 (-790 4160);
PAINT MONO (-790 4160);
FORCEPROP 0 LASTPIN (-800 4200) $PN 77
J 0
(-790 4210);
DISPLAY 0.680851 (-790 4210);
PAINT MONO (-790 4210);
FORCEPROP 0 LASTPIN (-800 4250) $PN 79
J 0
(-790 4260);
DISPLAY 0.680851 (-790 4260);
PAINT MONO (-790 4260);
FORCEPROP 0 LASTPIN (-800 4300) $PN 81
J 0
(-790 4310);
DISPLAY 0.680851 (-790 4310);
PAINT MONO (-790 4310);
FORCEPROP 0 LASTPIN (-800 4350) $PN 83
J 0
(-790 4360);
DISPLAY 0.680851 (-790 4360);
PAINT MONO (-790 4360);
FORCEPROP 0 LASTPIN (-800 4400) $PN 85
J 0
(-790 4410);
DISPLAY 0.680851 (-790 4410);
PAINT MONO (-790 4410);
FORCEPROP 0 LASTPIN (-800 4450) $PN 88
J 0
(-790 4460);
DISPLAY 0.680851 (-790 4460);
PAINT MONO (-790 4460);
FORCEPROP 0 LASTPIN (-800 4500) $PN 90
J 0
(-790 4510);
DISPLAY 0.680851 (-790 4510);
PAINT MONO (-790 4510);
FORCEPROP 0 LASTPIN (-800 4550) $PN 92
J 0
(-790 4560);
DISPLAY 0.680851 (-790 4560);
PAINT MONO (-790 4560);
FORCEPROP 0 LASTPIN (-800 4600) $PN 95
J 0
(-790 4610);
DISPLAY 0.680851 (-790 4610);
PAINT MONO (-790 4610);
FORCEPROP 0 LASTPIN (-800 4650) $PN 97
J 0
(-790 4660);
DISPLAY 0.680851 (-790 4660);
PAINT MONO (-790 4660);
FORCEPROP 0 LASTPIN (-800 4700) $PN 99
J 0
(-790 4710);
DISPLAY 0.680851 (-790 4710);
PAINT MONO (-790 4710);
FORCEPROP 0 LASTPIN (-800 4750) $PN 101
J 0
(-790 4760);
DISPLAY 0.680851 (-790 4760);
PAINT MONO (-790 4760);
FORCEPROP 0 LASTPIN (-800 4800) $PN 103
J 0
(-790 4810);
DISPLAY 0.680851 (-790 4810);
PAINT MONO (-790 4810);
FORCEPROP 0 LASTPIN (-800 4850) $PN 106
J 0
(-790 4860);
DISPLAY 0.680851 (-790 4860);
PAINT MONO (-790 4860);
FORCEPROP 0 LASTPIN (-800 4900) $PN 108
J 0
(-790 4910);
DISPLAY 0.680851 (-790 4910);
PAINT MONO (-790 4910);
FORCEPROP 0 LASTPIN (-800 4950) $PN 110
J 0
(-790 4960);
DISPLAY 0.680851 (-790 4960);
PAINT MONO (-790 4960);
FORCEPROP 0 LASTPIN (-800 5000) $PN 112
J 0
(-790 5010);
DISPLAY 0.680851 (-790 5010);
PAINT MONO (-790 5010);
FORCEPROP 0 LASTPIN (-800 5050) $PN 114
J 0
(-790 5060);
DISPLAY 0.680851 (-790 5060);
PAINT MONO (-790 5060);
FORCEPROP 0 LASTPIN (-800 5100) $PN 117
J 0
(-790 5110);
DISPLAY 0.680851 (-790 5110);
PAINT MONO (-790 5110);
FORCEPROP 0 LASTPIN (-800 5150) $PN 119
J 0
(-790 5160);
DISPLAY 0.680851 (-790 5160);
PAINT MONO (-790 5160);
FORCEPROP 0 LASTPIN (-800 5200) $PN 121
J 0
(-790 5210);
DISPLAY 0.680851 (-790 5210);
PAINT MONO (-790 5210);
FORCEPROP 0 LASTPIN (-800 5250) $PN 123
J 0
(-790 5260);
DISPLAY 0.680851 (-790 5260);
PAINT MONO (-790 5260);
FORCEPROP 0 LASTPIN (-800 5300) $PN 125
J 0
(-790 5310);
DISPLAY 0.680851 (-790 5310);
PAINT MONO (-790 5310);
FORCEPROP 0 LASTPIN (-800 5350) $PN 128
J 0
(-790 5360);
DISPLAY 0.680851 (-790 5360);
PAINT MONO (-790 5360);
FORCEPROP 0 LASTPIN (-800 5400) $PN 130
J 0
(-790 5410);
DISPLAY 0.680851 (-790 5410);
PAINT MONO (-790 5410);
FORCEPROP 0 LASTPIN (-800 5450) $PN 132
J 0
(-790 5460);
DISPLAY 0.680851 (-790 5460);
PAINT MONO (-790 5460);
FORCEPROP 0 LASTPIN (-800 5500) $PN 134
J 0
(-790 5510);
DISPLAY 0.680851 (-790 5510);
PAINT MONO (-790 5510);
FORCEPROP 0 LASTPIN (-800 5550) $PN 136
J 0
(-790 5560);
DISPLAY 0.680851 (-790 5560);
PAINT MONO (-790 5560);
FORCEPROP 0 LASTPIN (-800 5600) $PN 139
J 0
(-790 5610);
DISPLAY 0.680851 (-790 5610);
PAINT MONO (-790 5610);
FORCEPROP 0 LASTPIN (-800 5650) $PN 141
J 0
(-790 5660);
DISPLAY 0.680851 (-790 5660);
PAINT MONO (-790 5660);
FORCEPROP 0 LASTPIN (-800 5700) $PN 143
J 0
(-790 5710);
DISPLAY 0.680851 (-790 5710);
PAINT MONO (-790 5710);
FORCEPROP 0 LASTPIN (-2000 2450) $PN 151
J 2
(-2010 2460);
DISPLAY 0.680851 (-2010 2460);
PAINT MONO (-2010 2460);
FORCEPROP 0 LASTPIN (-2000 2500) $PN 153
J 2
(-2010 2510);
DISPLAY 0.680851 (-2010 2510);
PAINT MONO (-2010 2510);
FORCEPROP 0 LASTPIN (-2000 2550) $PN 155
J 2
(-2010 2560);
DISPLAY 0.680851 (-2010 2560);
PAINT MONO (-2010 2560);
FORCEPROP 0 LASTPIN (-2000 2600) $PN 158
J 2
(-2010 2610);
DISPLAY 0.680851 (-2010 2610);
PAINT MONO (-2010 2610);
FORCEPROP 0 LASTPIN (-2000 2650) $PN 160
J 2
(-2010 2660);
DISPLAY 0.680851 (-2010 2660);
PAINT MONO (-2010 2660);
FORCEPROP 0 LASTPIN (-2000 2700) $PN 162
J 2
(-2010 2710);
DISPLAY 0.680851 (-2010 2710);
PAINT MONO (-2010 2710);
FORCEPROP 0 LASTPIN (-2000 2750) $PN 164
J 2
(-2010 2760);
DISPLAY 0.680851 (-2010 2760);
PAINT MONO (-2010 2760);
FORCEPROP 0 LASTPIN (-2000 2800) $PN 166
J 2
(-2010 2810);
DISPLAY 0.680851 (-2010 2810);
PAINT MONO (-2010 2810);
FORCEPROP 0 LASTPIN (-2000 2850) $PN 169
J 2
(-2010 2860);
DISPLAY 0.680851 (-2010 2860);
PAINT MONO (-2010 2860);
FORCEPROP 0 LASTPIN (-2000 2900) $PN 171
J 2
(-2010 2910);
DISPLAY 0.680851 (-2010 2910);
PAINT MONO (-2010 2910);
FORCEPROP 0 LASTPIN (-2000 2950) $PN 173
J 2
(-2010 2960);
DISPLAY 0.680851 (-2010 2960);
PAINT MONO (-2010 2960);
FORCEPROP 0 LASTPIN (-2000 3000) $PN 175
J 2
(-2010 3010);
DISPLAY 0.680851 (-2010 3010);
PAINT MONO (-2010 3010);
FORCEPROP 0 LASTPIN (-2000 3050) $PN 177
J 2
(-2010 3060);
DISPLAY 0.680851 (-2010 3060);
PAINT MONO (-2010 3060);
FORCEPROP 0 LASTPIN (-2000 3100) $PN 180
J 2
(-2010 3110);
DISPLAY 0.680851 (-2010 3110);
PAINT MONO (-2010 3110);
FORCEPROP 0 LASTPIN (-2000 3150) $PN 182
J 2
(-2010 3160);
DISPLAY 0.680851 (-2010 3160);
PAINT MONO (-2010 3160);
FORCEPROP 0 LASTPIN (-2000 3200) $PN 184
J 2
(-2010 3210);
DISPLAY 0.680851 (-2010 3210);
PAINT MONO (-2010 3210);
FORCEPROP 0 LASTPIN (-2000 3250) $PN 186
J 2
(-2010 3260);
DISPLAY 0.680851 (-2010 3260);
PAINT MONO (-2010 3260);
FORCEPROP 0 LASTPIN (-2000 3300) $PN 188
J 2
(-2010 3310);
DISPLAY 0.680851 (-2010 3310);
PAINT MONO (-2010 3310);
FORCEPROP 0 LASTPIN (-2000 3350) $PN 191
J 2
(-2010 3360);
DISPLAY 0.680851 (-2010 3360);
PAINT MONO (-2010 3360);
FORCEPROP 0 LASTPIN (-2000 3400) $PN 193
J 2
(-2010 3410);
DISPLAY 0.680851 (-2010 3410);
PAINT MONO (-2010 3410);
FORCEPROP 0 LASTPIN (-2000 3450) $PN 195
J 2
(-2010 3460);
DISPLAY 0.680851 (-2010 3460);
PAINT MONO (-2010 3460);
FORCEPROP 0 LASTPIN (-2000 3500) $PN 197
J 2
(-2010 3510);
DISPLAY 0.680851 (-2010 3510);
PAINT MONO (-2010 3510);
FORCEPROP 0 LASTPIN (-2000 3550) $PN 199
J 2
(-2010 3560);
DISPLAY 0.680851 (-2010 3560);
PAINT MONO (-2010 3560);
FORCEPROP 0 LASTPIN (-2000 3600) $PN 202
J 2
(-2010 3610);
DISPLAY 0.680851 (-2010 3610);
PAINT MONO (-2010 3610);
FORCEPROP 0 LASTPIN (-2000 3650) $PN 204
J 2
(-2010 3660);
DISPLAY 0.680851 (-2010 3660);
PAINT MONO (-2010 3660);
FORCEPROP 0 LASTPIN (-2000 3700) $PN 206
J 2
(-2010 3710);
DISPLAY 0.680851 (-2010 3710);
PAINT MONO (-2010 3710);
FORCEPROP 0 LASTPIN (-2000 3750) $PN 208
J 2
(-2010 3760);
DISPLAY 0.680851 (-2010 3760);
PAINT MONO (-2010 3760);
FORCEPROP 0 LASTPIN (-2000 3800) $PN 210
J 2
(-2010 3810);
DISPLAY 0.680851 (-2010 3810);
PAINT MONO (-2010 3810);
FORCEPROP 0 LASTPIN (-2000 3850) $PN 212
J 2
(-2010 3860);
DISPLAY 0.680851 (-2010 3860);
PAINT MONO (-2010 3860);
FORCEPROP 0 LASTPIN (-2000 3900) $PN 214
J 2
(-2010 3910);
DISPLAY 0.680851 (-2010 3910);
PAINT MONO (-2010 3910);
FORCEPROP 0 LASTPIN (-2000 3950) $PN 216
J 2
(-2010 3960);
DISPLAY 0.680851 (-2010 3960);
PAINT MONO (-2010 3960);
FORCEPROP 0 LASTPIN (-2000 4000) $PN 219
J 2
(-2010 4010);
DISPLAY 0.680851 (-2010 4010);
PAINT MONO (-2010 4010);
FORCEPROP 0 LASTPIN (-2000 4050) $PN 222
J 2
(-2010 4060);
DISPLAY 0.680851 (-2010 4060);
PAINT MONO (-2010 4060);
FORCEPROP 0 LASTPIN (-2000 4100) $PN 224
J 2
(-2010 4110);
DISPLAY 0.680851 (-2010 4110);
PAINT MONO (-2010 4110);
FORCEPROP 0 LASTPIN (-2000 4150) $PN 226
J 2
(-2010 4160);
DISPLAY 0.680851 (-2010 4160);
PAINT MONO (-2010 4160);
FORCEPROP 0 LASTPIN (-2000 4200) $PN 228
J 2
(-2010 4210);
DISPLAY 0.680851 (-2010 4210);
PAINT MONO (-2010 4210);
FORCEPROP 0 LASTPIN (-2000 4250) $PN 230
J 2
(-2010 4260);
DISPLAY 0.680851 (-2010 4260);
PAINT MONO (-2010 4260);
FORCEPROP 0 LASTPIN (-2000 4300) $PN 233
J 2
(-2010 4310);
DISPLAY 0.680851 (-2010 4310);
PAINT MONO (-2010 4310);
FORCEPROP 0 LASTPIN (-2000 4350) $PN 235
J 2
(-2010 4360);
DISPLAY 0.680851 (-2010 4360);
PAINT MONO (-2010 4360);
FORCEPROP 0 LASTPIN (-2000 4400) $PN 237
J 2
(-2010 4410);
DISPLAY 0.680851 (-2010 4410);
PAINT MONO (-2010 4410);
FORCEPROP 0 LASTPIN (-2000 4450) $PN 240
J 2
(-2010 4460);
DISPLAY 0.680851 (-2010 4460);
PAINT MONO (-2010 4460);
FORCEPROP 0 LASTPIN (-2000 4500) $PN 242
J 2
(-2010 4510);
DISPLAY 0.680851 (-2010 4510);
PAINT MONO (-2010 4510);
FORCEPROP 0 LASTPIN (-2000 4550) $PN 244
J 2
(-2010 4560);
DISPLAY 0.680851 (-2010 4560);
PAINT MONO (-2010 4560);
FORCEPROP 0 LASTPIN (-2000 4600) $PN 246
J 2
(-2010 4610);
DISPLAY 0.680851 (-2010 4610);
PAINT MONO (-2010 4610);
FORCEPROP 0 LASTPIN (-2000 4650) $PN 248
J 2
(-2010 4660);
DISPLAY 0.680851 (-2010 4660);
PAINT MONO (-2010 4660);
FORCEPROP 0 LASTPIN (-2000 4700) $PN 251
J 2
(-2010 4710);
DISPLAY 0.680851 (-2010 4710);
PAINT MONO (-2010 4710);
FORCEPROP 0 LASTPIN (-2000 4750) $PN 253
J 2
(-2010 4760);
DISPLAY 0.680851 (-2010 4760);
PAINT MONO (-2010 4760);
FORCEPROP 0 LASTPIN (-2000 4800) $PN 255
J 2
(-2010 4810);
DISPLAY 0.680851 (-2010 4810);
PAINT MONO (-2010 4810);
FORCEPROP 0 LASTPIN (-2000 4850) $PN 257
J 2
(-2010 4860);
DISPLAY 0.680851 (-2010 4860);
PAINT MONO (-2010 4860);
FORCEPROP 0 LASTPIN (-2000 4900) $PN 259
J 2
(-2010 4910);
DISPLAY 0.680851 (-2010 4910);
PAINT MONO (-2010 4910);
FORCEPROP 0 LASTPIN (-2000 4950) $PN 262
J 2
(-2010 4960);
DISPLAY 0.680851 (-2010 4960);
PAINT MONO (-2010 4960);
FORCEPROP 0 LASTPIN (-2000 5000) $PN 264
J 2
(-2010 5010);
DISPLAY 0.680851 (-2010 5010);
PAINT MONO (-2010 5010);
FORCEPROP 0 LASTPIN (-2000 5050) $PN 266
J 2
(-2010 5060);
DISPLAY 0.680851 (-2010 5060);
PAINT MONO (-2010 5060);
FORCEPROP 0 LASTPIN (-2000 5100) $PN 268
J 2
(-2010 5110);
DISPLAY 0.680851 (-2010 5110);
PAINT MONO (-2010 5110);
FORCEPROP 0 LASTPIN (-2000 5150) $PN 270
J 2
(-2010 5160);
DISPLAY 0.680851 (-2010 5160);
PAINT MONO (-2010 5160);
FORCEPROP 0 LASTPIN (-2000 5200) $PN 273
J 2
(-2010 5210);
DISPLAY 0.680851 (-2010 5210);
PAINT MONO (-2010 5210);
FORCEPROP 0 LASTPIN (-2000 5250) $PN 275
J 2
(-2010 5260);
DISPLAY 0.680851 (-2010 5260);
PAINT MONO (-2010 5260);
FORCEPROP 0 LASTPIN (-2000 5300) $PN 277
J 2
(-2010 5310);
DISPLAY 0.680851 (-2010 5310);
PAINT MONO (-2010 5310);
FORCEPROP 0 LASTPIN (-2000 5350) $PN 279
J 2
(-2010 5360);
DISPLAY 0.680851 (-2010 5360);
PAINT MONO (-2010 5360);
FORCEPROP 0 LASTPIN (-2000 5400) $PN 281
J 2
(-2010 5410);
DISPLAY 0.680851 (-2010 5410);
PAINT MONO (-2010 5410);
FORCEPROP 0 LASTPIN (-2000 5450) $PN 284
J 2
(-2010 5460);
DISPLAY 0.680851 (-2010 5460);
PAINT MONO (-2010 5460);
FORCEPROP 0 LASTPIN (-2000 5500) $PN 286
J 2
(-2010 5510);
DISPLAY 0.680851 (-2010 5510);
PAINT MONO (-2010 5510);
FORCEPROP 0 LASTPIN (-2000 5550) $PN 288
J 2
(-2010 5560);
DISPLAY 0.680851 (-2010 5560);
PAINT MONO (-2010 5560);
FORCEPROP 2 LAST PART_TYPE SMLF
J 0
(-1850 6125);
DISPLAY 1.021277 (-1850 6125);
FORCEPROP 2 LAST VALUE SCONN288_DDR506112002KQ
J 0
(-1850 6075);
DISPLAY 0.489362 (-1850 6075);
PAINT SKYBLUE (-1850 6075);
FORCEPROP 1 LAST MATERIAL IO
J 0
(-1850 5875);
DISPLAY 0.468085 (-1850 5875);
PAINT SKYBLUE (-1850 5875);
FORCEPROP 1 LAST PART_NUMBER DFHST8FS479
J 0
(-1850 5950);
DISPLAY 0.468085 (-1850 5950);
PAINT SKYBLUE (-1850 5950);
FORCEPROP 1 LAST CDS_LMAN_SYM_OUTLINE -450,1800,450,-1750
J 0
(-1400 4050);
DISPLAY 0.468085 (-1400 4050);
PAINT GREEN (-1400 4050);
DISPLAY INVISIBLE (-1400 4050);
FORCEPROP 1 LAST PATH I352
J 0
(-1400 4050);
DISPLAY 0.723404 (-1400 4050);
PAINT GREEN (-1400 4050);
DISPLAY INVISIBLE (-1400 4050);
FORCEPROP 1 LAST NEEDS_NO_SIZE TRUE
J 0
(-1400 4050);
DISPLAY 0.723404 (-1400 4050);
PAINT GREEN (-1400 4050);
DISPLAY INVISIBLE (-1400 4050);
FORCEPROP 2 LAST CDS_LIB pure_quanta
J 0
(-1400 4050);
DISPLAY INVISIBLE (-1400 4050);
FORCEADD OFFPAGE..5
(-8525 3375);
FORCEPROP 2 LAST $XR0 12 
J 0
(-8779 3375);
DISPLAY 0.638298 (-8779 3375);
PAINT MONO (-8779 3375);
FORCEPROP 2 LAST PATH I353
J 0
(-8475 3450);
DISPLAY 1.021277 (-8475 3450);
DISPLAY INVISIBLE (-8475 3450);
FORCEPROP 1 LAST COMMENT_BODY TRUE
J 0
(-8425 3300);
DISPLAY 0.872340 (-8425 3300);
PAINT GREEN (-8425 3300);
DISPLAY INVISIBLE (-8425 3300);
FORCEPROP 1 LAST OFFPAGE TRUE
J 0
(-8200 3250);
DISPLAY 0.872340 (-8200 3250);
PAINT GREEN (-8200 3250);
DISPLAY INVISIBLE (-8200 3250);
FORCEPROP 2 LAST CDS_LIB mstr_standard
J 0
(-8525 3375);
DISPLAY INVISIBLE (-8525 3375);
FORCEADD OFFPAGE..6
(-8525 3175);
FORCEPROP 2 LAST $XR5 136 
J 0
(-9254 3175);
DISPLAY 0.638298 (-9254 3175);
PAINT MONO (-9254 3175);
FORCEPROP 2 LAST $XR4 90 
J 0
(-9134 3175);
DISPLAY 0.638298 (-9134 3175);
PAINT MONO (-9134 3175);
FORCEPROP 2 LAST $XR3 89 
J 0
(-9044 3175);
DISPLAY 0.638298 (-9044 3175);
PAINT MONO (-9044 3175);
FORCEPROP 2 LAST $XR2 88 
J 0
(-8954 3175);
DISPLAY 0.638298 (-8954 3175);
PAINT MONO (-8954 3175);
FORCEPROP 2 LAST $XR1 86 
J 0
(-8864 3175);
DISPLAY 0.638298 (-8864 3175);
PAINT MONO (-8864 3175);
FORCEPROP 2 LAST $XR0 85 
J 0
(-8774 3175);
DISPLAY 0.638298 (-8774 3175);
PAINT MONO (-8774 3175);
FORCEPROP 2 LAST PATH I355
J 0
(-8800 3225);
DISPLAY 1.021277 (-8800 3225);
DISPLAY INVISIBLE (-8800 3225);
FORCEPROP 1 LAST COMMENT_BODY TRUE
J 0
(-8425 3100);
DISPLAY 0.872340 (-8425 3100);
PAINT GREEN (-8425 3100);
DISPLAY INVISIBLE (-8425 3100);
FORCEPROP 1 LAST OFFPAGE TRUE
J 0
(-8200 3050);
DISPLAY 0.872340 (-8200 3050);
PAINT GREEN (-8200 3050);
DISPLAY INVISIBLE (-8200 3050);
FORCEPROP 2 LAST CDS_LIB mstr_standard
J 0
(-8525 3175);
DISPLAY 0.808511 (-8525 3175);
DISPLAY INVISIBLE (-8525 3175);
FORCEADD GND..1
(-8925 3300);
FORCEPROP 3 LASTPIN (-8925 3350) SIG_NAME GND\g
J 0
(-8915 3360);
DISPLAY 0.659574 (-8915 3360);
PAINT MONO (-8915 3360);
DISPLAY INVISIBLE (-8915 3360);
FORCEPROP 2 LAST BOM_COST MEM
J 0
(-8900 3425);
DISPLAY 0.659574 (-8900 3425);
DISPLAY INVISIBLE (-8900 3425);
FORCEPROP 1 LAST SIZE 1B
J 0
(-8850 3250);
DISPLAY 0.723404 (-8850 3250);
PAINT GREEN (-8850 3250);
DISPLAY INVISIBLE (-8850 3250);
FORCEPROP 2 LAST CDS_LIB mstr_symbols
J 0
(-8925 3300);
DISPLAY 0.808511 (-8925 3300);
DISPLAY INVISIBLE (-8925 3300);
FORCEPROP 1 LAST BODY_TYPE PLUMBING
J 0
(-8970 3257);
DISPLAY 0.276596 (-8970 3257);
PAINT GREEN (-8970 3257);
DISPLAY INVISIBLE (-8970 3257);
FORCEPROP 1 LAST PATH I361
J 0
(-8850 3300);
DISPLAY 0.872340 (-8850 3300);
PAINT AQUA (-8850 3300);
DISPLAY INVISIBLE (-8850 3300);
FORCEPROP 1 LAST VOLTAGE 0
J 0
(-8945 3395);
DISPLAY 0.829787 (-8945 3395);
PAINT SKYBLUE (-8945 3395);
DISPLAY INVISIBLE (-8945 3395);
FORCEPROP 2 LAST ROOM MEM_EFGH_DECOUPLING_CAPS
J 0
(-8900 3375);
DISPLAY 0.659574 (-8900 3375);
PAINT RED (-8900 3375);
DISPLAY INVISIBLE (-8900 3375);
FORCEPROP 1 LAST HDL_POWER GND
J 0
(-8925 3450);
DISPLAY 0.723404 (-8925 3450);
PAINT GREEN (-8925 3450);
DISPLAY INVISIBLE (-8925 3450);
FORCEADD Q_CAP..1
R 2
(-8925 3525);
FORCEPROP 1 LAST LOCATION C96
J 2
(-8975 3625);
DISPLAY 0.489362 (-8975 3625);
PAINT SKYBLUE (-8975 3625);
FORCEPROP 0 LAST $SEC 1
J 0
(-8975 3675);
DISPLAY 0.680851 (-8975 3675);
PAINT MONO (-8975 3675);
DISPLAY INVISIBLE (-8975 3675);
FORCEPROP 0 LAST CDS_SEC 1
J 0
(-8975 3675);
DISPLAY 1.021277 (-8975 3675);
DISPLAY INVISIBLE (-8975 3675);
FORCEPROP 1 LASTPIN (-8925 3625) $PN 1
J 2
(-8935 3605);
DISPLAY 0.489362 (-8935 3605);
PAINT MONO (-8935 3605);
FORCEPROP 1 LASTPIN (-8925 3425) $PN 2
J 2
(-8935 3405);
DISPLAY 0.489362 (-8935 3405);
PAINT MONO (-8935 3405);
FORCEPROP 1 LAST TOLERANCE 10%
J 2
(-8975 3475);
DISPLAY 0.489362 (-8975 3475);
PAINT SKYBLUE (-8975 3475);
FORCEPROP 1 LAST VALUE 0.1UF
J 2
(-8975 3575);
DISPLAY 0.489362 (-8975 3575);
PAINT SKYBLUE (-8975 3575);
FORCEPROP 1 LAST PART_NUMBER CH4104K1B00
J 2
(-8975 3375);
DISPLAY 0.489362 (-8975 3375);
PAINT SKYBLUE (-8975 3375);
FORCEPROP 1 LAST VOLTAGE 25V
J 2
(-8975 3525);
DISPLAY 0.489362 (-8975 3525);
PAINT SKYBLUE (-8975 3525);
FORCEPROP 1 LAST PACK_TYPE 0402
J 2
(-8975 3325);
DISPLAY 0.489362 (-8975 3325);
PAINT SKYBLUE (-8975 3325);
FORCEPROP 1 LAST MATERIAL X7R
J 2
(-8975 3425);
DISPLAY 0.489362 (-8975 3425);
PAINT SKYBLUE (-8975 3425);
FORCEPROP 0 LAST BOM_COST MEM
J 2
(-8980 3670);
DISPLAY 0.595745 (-8980 3670);
PAINT MONO (-8980 3670);
DISPLAY INVISIBLE (-8980 3670);
FORCEPROP 2 LAST CDS_LIB pure_quanta
J 0
(-8925 3525);
DISPLAY INVISIBLE (-8925 3525);
FORCEPROP 1 LAST PATH I362
J 2
(-8975 3675);
DISPLAY 0.978723 (-8975 3675);
PAINT WHITE (-8975 3675);
DISPLAY INVISIBLE (-8975 3675);
FORCEPROP 0 LAST ROOM MEM_CH_A_CPU0_DIMM1
J 2
(-8980 3670);
DISPLAY 0.595745 (-8980 3670);
PAINT RED (-8980 3670);
DISPLAY INVISIBLE (-8980 3670);
FORCEADD OFFPAGE..6
(-9175 2475);
FORCEPROP 2 LAST $XR5 81 
J 0
(-9544 2511);
DISPLAY 0.638298 (-9544 2511);
PAINT MONO (-9544 2511);
FORCEPROP 2 LAST $XR4 90 
J 0
(-9454 2511);
DISPLAY 0.638298 (-9454 2511);
PAINT MONO (-9454 2511);
FORCEPROP 2 LAST $XR3 89 
J 0
(-9544 2439);
DISPLAY 0.638298 (-9544 2439);
PAINT MONO (-9544 2439);
FORCEPROP 2 LAST $XR2 88 
J 0
(-9454 2439);
DISPLAY 0.638298 (-9454 2439);
PAINT MONO (-9454 2439);
FORCEPROP 2 LAST $XR1 86 
J 0
(-9544 2475);
DISPLAY 0.638298 (-9544 2475);
PAINT MONO (-9544 2475);
FORCEPROP 2 LAST $XR0 85 
J 0
(-9454 2475);
DISPLAY 0.638298 (-9454 2475);
PAINT MONO (-9454 2475);
FORCEPROP 2 LAST PATH I363
J 0
(-9125 2550);
DISPLAY 1.021277 (-9125 2550);
DISPLAY INVISIBLE (-9125 2550);
FORCEPROP 1 LAST COMMENT_BODY TRUE
J 0
(-9075 2400);
DISPLAY 0.872340 (-9075 2400);
PAINT GREEN (-9075 2400);
DISPLAY INVISIBLE (-9075 2400);
FORCEPROP 1 LAST OFFPAGE TRUE
J 0
(-8850 2350);
DISPLAY 0.872340 (-8850 2350);
PAINT GREEN (-8850 2350);
DISPLAY INVISIBLE (-8850 2350);
FORCEPROP 2 LAST CDS_LIB mstr_standard
J 0
(-9175 2475);
DISPLAY 0.808511 (-9175 2475);
DISPLAY INVISIBLE (-9175 2475);
FORCEADD Q_RES..1
R 2
(-8675 2475);
FORCEPROP 1 LAST LOCATION R293
J 2
(-8650 2500);
DISPLAY 0.489362 (-8650 2500);
PAINT SKYBLUE (-8650 2500);
FORCEPROP 0 LAST $SEC 1
J 0
(-8650 2550);
DISPLAY 0.680851 (-8650 2550);
PAINT MONO (-8650 2550);
DISPLAY INVISIBLE (-8650 2550);
FORCEPROP 0 LAST CDS_SEC 1
J 0
(-8650 2550);
DISPLAY 1.021277 (-8650 2550);
DISPLAY INVISIBLE (-8650 2550);
FORCEPROP 1 LASTPIN (-8575 2475) $PN 1
J 2
(-8587 2487);
DISPLAY 0.489362 (-8587 2487);
PAINT MONO (-8587 2487);
FORCEPROP 1 LASTPIN (-8775 2475) $PN 2
J 2
(-8737 2487);
DISPLAY 0.489362 (-8737 2487);
PAINT MONO (-8737 2487);
FORCEPROP 1 LAST VALUE 0
J 0
(-8675 2425);
DISPLAY 0.489362 (-8675 2425);
PAINT SKYBLUE (-8675 2425);
FORCEPROP 2 LAST BOM_COST MEM
J 0
(-8700 2625);
DISPLAY 0.744681 (-8700 2625);
PAINT WHITE (-8700 2625);
DISPLAY INVISIBLE (-8700 2625);
FORCEPROP 2 LAST CDS_LIB pure_quanta
J 0
(-8675 2475);
DISPLAY INVISIBLE (-8675 2475);
FORCEPROP 1 LAST PATH I364
J 2
(-8625 2625);
DISPLAY 0.978723 (-8625 2625);
PAINT WHITE (-8625 2625);
DISPLAY INVISIBLE (-8625 2625);
FORCEPROP 1 LAST WATTAGE 1/16W
J 0
(-8600 2400);
DISPLAY 0.489362 (-8600 2400);
PAINT SKYBLUE (-8600 2400);
DISPLAY INVISIBLE (-8600 2400);
FORCEPROP 1 LAST MATERIAL CHIP
J 0
(-8850 2450);
DISPLAY 0.489362 (-8850 2450);
PAINT SKYBLUE (-8850 2450);
DISPLAY INVISIBLE (-8850 2450);
FORCEPROP 1 LAST TOLERANCE 5%
J 2
(-8550 2450);
DISPLAY 0.489362 (-8550 2450);
PAINT SKYBLUE (-8550 2450);
DISPLAY INVISIBLE (-8550 2450);
FORCEPROP 1 LAST PART_NUMBER CS00002JB38
J 0
(-8775 2525);
DISPLAY 0.489362 (-8775 2525);
PAINT SKYBLUE (-8775 2525);
DISPLAY INVISIBLE (-8775 2525);
FORCEPROP 1 LAST PACK_TYPE 0402LF
J 0
(-8850 2400);
DISPLAY 0.489362 (-8850 2400);
PAINT SKYBLUE (-8850 2400);
DISPLAY INVISIBLE (-8850 2400);
FORCEPROP 2 LAST ROOM RST_CPU0_PLD_TO_DIMM
J 0
(-8700 2575);
DISPLAY 0.744681 (-8700 2575);
PAINT RED (-8700 2575);
DISPLAY INVISIBLE (-8700 2575);
FORCEADD Q_RES..2
(-8550 2625);
FORCEPROP 1 LAST LOCATION R91
J 0
(-8505 2750);
DISPLAY 0.489362 (-8505 2750);
PAINT SKYBLUE (-8505 2750);
FORCEPROP 0 LAST $SEC 1
J 0
(-8500 2800);
DISPLAY 0.680851 (-8500 2800);
PAINT MONO (-8500 2800);
DISPLAY INVISIBLE (-8500 2800);
FORCEPROP 0 LAST CDS_SEC 1
J 0
(-8500 2800);
DISPLAY 1.021277 (-8500 2800);
DISPLAY INVISIBLE (-8500 2800);
FORCEPROP 1 LASTPIN (-8550 2725) $PN 1
J 0
(-8545 2687);
DISPLAY 0.489362 (-8545 2687);
PAINT MONO (-8545 2687);
FORCEPROP 1 LASTPIN (-8550 2525) $PN 2
J 0
(-8545 2535);
DISPLAY 0.489362 (-8545 2535);
PAINT MONO (-8545 2535);
FORCEPROP 1 LAST PACK_TYPE 0402LF
J 0
(-8500 2575);
DISPLAY 0.489362 (-8500 2575);
PAINT SKYBLUE (-8500 2575);
FORCEPROP 1 LAST VALUE 1K
J 0
(-8505 2700);
DISPLAY 0.489362 (-8505 2700);
PAINT SKYBLUE (-8505 2700);
FORCEPROP 1 LAST TOLERANCE 5%
J 0
(-8500 2675);
DISPLAY 0.489362 (-8500 2675);
PAINT SKYBLUE (-8500 2675);
FORCEPROP 1 LAST WATTAGE 1/16W
J 0
(-8500 2650);
DISPLAY 0.489362 (-8500 2650);
PAINT SKYBLUE (-8500 2650);
FORCEPROP 1 LAST MATERIAL EMPTY
J 0
(-8500 2625);
DISPLAY 0.489362 (-8500 2625);
PAINT RED (-8500 2625);
FORCEPROP 2 LAST CDS_LIB pure_quanta
J 2
(-8550 2625);
DISPLAY INVISIBLE (-8550 2625);
FORCEPROP 2 LAST BOM_COST MEM
J 0
(-8500 2800);
DISPLAY 0.808511 (-8500 2800);
DISPLAY INVISIBLE (-8500 2800);
FORCEPROP 1 LAST PATH I365
J 0
(-8500 2800);
DISPLAY 0.978723 (-8500 2800);
PAINT WHITE (-8500 2800);
DISPLAY INVISIBLE (-8500 2800);
FORCEPROP 1 LAST PART_NUMBER TMP_QCS21002JB34
J 0
(-8500 2600);
DISPLAY 0.489362 (-8500 2600);
PAINT SKYBLUE (-8500 2600);
DISPLAY INVISIBLE (-8500 2600);
FORCEPROP 2 LAST ROOM MEM_CH_A_CPU0_DIMM1
J 0
(-8500 2850);
DISPLAY 0.808511 (-8500 2850);
PAINT RED (-8500 2850);
DISPLAY INVISIBLE (-8500 2850);
FORCEADD VCC_CORE..1
(-8550 2800);
FORCEPROP 3 LASTPIN (-8550 2750) SIG_NAME P3V3_STBY\g
J 0
(-8540 2760);
DISPLAY 0.659574 (-8540 2760);
PAINT MONO (-8540 2760);
DISPLAY INVISIBLE (-8540 2760);
FORCEPROP 1 LAST HDL_POWER P3V3_STBY
J 1
(-8550 2850);
DISPLAY 0.489362 (-8550 2850);
PAINT GREEN (-8550 2850);
FORCEPROP 2 LAST CDS_LIB mstr_symbols
J 0
(-8550 2800);
DISPLAY INVISIBLE (-8550 2800);
FORCEPROP 1 LAST PATH I366
J 0
(-8500 2825);
DISPLAY 0.872340 (-8500 2825);
PAINT AQUA (-8500 2825);
DISPLAY INVISIBLE (-8500 2825);
FORCEPROP 0 LAST VOLTAGE 3.3
J 0
(-8825 2950);
DISPLAY 1.021277 (-8825 2950);
PAINT SKYBLUE (-8825 2950);
DISPLAY INVISIBLE (-8825 2950);
FORCEPROP 2 LAST ROOM PVCCINFAON_CPU0_CTRL
J 0
(-8550 2900);
DISPLAY 0.808511 (-8550 2900);
PAINT RED (-8550 2900);
DISPLAY INVISIBLE (-8550 2900);
FORCEADD OFFPAGE..2
(-2725 3900);
FORCEPROP 2 LAST $XR0 12 
J 0
(-2536 3900);
DISPLAY 0.638298 (-2536 3900);
PAINT MONO (-2536 3900);
FORCEPROP 2 LAST PATH I367
J 0
(-2525 3950);
DISPLAY 0.680851 (-2525 3950);
DISPLAY INVISIBLE (-2525 3950);
FORCEPROP 1 LAST COMMENT_BODY TRUE
J 0
(-2770 3805);
DISPLAY 0.872340 (-2770 3805);
PAINT GREEN (-2770 3805);
DISPLAY INVISIBLE (-2770 3805);
FORCEPROP 1 LAST OFFPAGE TRUE
J 0
(-2400 3775);
DISPLAY 0.723404 (-2400 3775);
PAINT GREEN (-2400 3775);
DISPLAY INVISIBLE (-2400 3775);
FORCEPROP 2 LAST CDS_LIB mstr_standard
J 0
(-2725 3900);
DISPLAY 0.723404 (-2725 3900);
PAINT MONO (-2725 3900);
DISPLAY INVISIBLE (-2725 3900);
FORCEADD OFFPAGE..2
(-2725 3950);
FORCEPROP 2 LAST $XR0 12 
J 0
(-2536 3950);
DISPLAY 0.638298 (-2536 3950);
PAINT MONO (-2536 3950);
FORCEPROP 2 LAST PATH I368
J 0
(-2525 4000);
DISPLAY 0.680851 (-2525 4000);
DISPLAY INVISIBLE (-2525 4000);
FORCEPROP 1 LAST COMMENT_BODY TRUE
J 0
(-2770 3855);
DISPLAY 0.872340 (-2770 3855);
PAINT GREEN (-2770 3855);
DISPLAY INVISIBLE (-2770 3855);
FORCEPROP 1 LAST OFFPAGE TRUE
J 0
(-2400 3825);
DISPLAY 0.723404 (-2400 3825);
PAINT GREEN (-2400 3825);
DISPLAY INVISIBLE (-2400 3825);
FORCEPROP 2 LAST CDS_LIB mstr_standard
J 0
(-2725 3950);
DISPLAY 0.723404 (-2725 3950);
PAINT MONO (-2725 3950);
DISPLAY INVISIBLE (-2725 3950);
FORCEADD OFFPAGE..2
(-2725 4950);
FORCEPROP 2 LAST $XR0 12 
J 0
(-2536 4950);
DISPLAY 0.638298 (-2536 4950);
PAINT MONO (-2536 4950);
FORCEPROP 2 LAST PATH I369
J 0
(-2525 5000);
DISPLAY 0.680851 (-2525 5000);
DISPLAY INVISIBLE (-2525 5000);
FORCEPROP 1 LAST COMMENT_BODY TRUE
J 0
(-2770 4855);
DISPLAY 0.872340 (-2770 4855);
PAINT GREEN (-2770 4855);
DISPLAY INVISIBLE (-2770 4855);
FORCEPROP 1 LAST OFFPAGE TRUE
J 0
(-2400 4825);
DISPLAY 0.723404 (-2400 4825);
PAINT GREEN (-2400 4825);
DISPLAY INVISIBLE (-2400 4825);
FORCEPROP 2 LAST CDS_LIB mstr_standard
J 0
(-2725 4950);
DISPLAY 0.723404 (-2725 4950);
PAINT MONO (-2725 4950);
DISPLAY INVISIBLE (-2725 4950);
FORCEADD OFFPAGE..2
(-2725 5000);
FORCEPROP 2 LAST $XR0 12 
J 0
(-2536 5000);
DISPLAY 0.638298 (-2536 5000);
PAINT MONO (-2536 5000);
FORCEPROP 2 LAST PATH I370
J 0
(-2525 5050);
DISPLAY 0.680851 (-2525 5050);
DISPLAY INVISIBLE (-2525 5050);
FORCEPROP 1 LAST COMMENT_BODY TRUE
J 0
(-2770 4905);
DISPLAY 0.872340 (-2770 4905);
PAINT GREEN (-2770 4905);
DISPLAY INVISIBLE (-2770 4905);
FORCEPROP 1 LAST OFFPAGE TRUE
J 0
(-2400 4875);
DISPLAY 0.723404 (-2400 4875);
PAINT GREEN (-2400 4875);
DISPLAY INVISIBLE (-2400 4875);
FORCEPROP 2 LAST CDS_LIB mstr_standard
J 0
(-2725 5000);
DISPLAY 0.723404 (-2725 5000);
PAINT MONO (-2725 5000);
DISPLAY INVISIBLE (-2725 5000);
FORCEADD TAP..1
(-3525 4900);
FORCEPROP 3 LASTPIN (-3575 4900) SIG_NAME M_C_CPU0_SA_DQS_DN<9>
J 0
(-3565 4910);
DISPLAY 0.659574 (-3565 4910);
PAINT MONO (-3565 4910);
DISPLAY INVISIBLE (-3565 4910);
FORCEPROP 1 LASTPIN (-3575 4900) BN 9
J 0
(-3587 4908);
DISPLAY 0.489362 (-3587 4908);
PAINT GREEN (-3587 4908);
FORCEPROP 2 LAST CDS_LIB mstr_standard
J 0
(-3525 4900);
DISPLAY 0.723404 (-3525 4900);
PAINT MONO (-3525 4900);
DISPLAY INVISIBLE (-3525 4900);
FORCEPROP 1 LAST BODY_TYPE PLUMBING
J 0
(-3525 4950);
DISPLAY 0.872340 (-3525 4950);
PAINT GREEN (-3525 4950);
DISPLAY INVISIBLE (-3525 4950);
FORCEPROP 1 LAST HDL_TAP TRUE
J 0
(-3200 4775);
DISPLAY 0.872340 (-3200 4775);
DISPLAY INVISIBLE (-3200 4775);
FORCEPROP 1 LAST PATH I371
J 0
(-3527 4900);
DISPLAY 0.872340 (-3527 4900);
PAINT GREEN (-3527 4900);
DISPLAY INVISIBLE (-3527 4900);
FORCEADD TAP..1
(-3525 4700);
FORCEPROP 3 LASTPIN (-3575 4700) SIG_NAME M_C_CPU0_SA_DQS_DN<7>
J 0
(-3565 4710);
DISPLAY 0.659574 (-3565 4710);
PAINT MONO (-3565 4710);
DISPLAY INVISIBLE (-3565 4710);
FORCEPROP 1 LASTPIN (-3575 4700) BN 7
J 0
(-3587 4708);
DISPLAY 0.489362 (-3587 4708);
PAINT GREEN (-3587 4708);
FORCEPROP 2 LAST CDS_LIB mstr_standard
J 0
(-3525 4700);
DISPLAY 0.723404 (-3525 4700);
PAINT MONO (-3525 4700);
DISPLAY INVISIBLE (-3525 4700);
FORCEPROP 1 LAST BODY_TYPE PLUMBING
J 0
(-3525 4750);
DISPLAY 0.872340 (-3525 4750);
PAINT GREEN (-3525 4750);
DISPLAY INVISIBLE (-3525 4750);
FORCEPROP 1 LAST HDL_TAP TRUE
J 0
(-3200 4575);
DISPLAY 0.872340 (-3200 4575);
DISPLAY INVISIBLE (-3200 4575);
FORCEPROP 1 LAST PATH I372
J 0
(-3527 4700);
DISPLAY 0.872340 (-3527 4700);
PAINT GREEN (-3527 4700);
DISPLAY INVISIBLE (-3527 4700);
FORCEADD TAP..1
(-3525 4800);
FORCEPROP 3 LASTPIN (-3575 4800) SIG_NAME M_C_CPU0_SA_DQS_DN<8>
J 0
(-3565 4810);
DISPLAY 0.659574 (-3565 4810);
PAINT MONO (-3565 4810);
DISPLAY INVISIBLE (-3565 4810);
FORCEPROP 1 LASTPIN (-3575 4800) BN 8
J 0
(-3587 4808);
DISPLAY 0.489362 (-3587 4808);
PAINT GREEN (-3587 4808);
FORCEPROP 2 LAST CDS_LIB mstr_standard
J 0
(-3525 4800);
DISPLAY 0.723404 (-3525 4800);
PAINT MONO (-3525 4800);
DISPLAY INVISIBLE (-3525 4800);
FORCEPROP 1 LAST BODY_TYPE PLUMBING
J 0
(-3525 4850);
DISPLAY 0.872340 (-3525 4850);
PAINT GREEN (-3525 4850);
DISPLAY INVISIBLE (-3525 4850);
FORCEPROP 1 LAST HDL_TAP TRUE
J 0
(-3200 4675);
DISPLAY 0.872340 (-3200 4675);
DISPLAY INVISIBLE (-3200 4675);
FORCEPROP 1 LAST PATH I373
J 0
(-3527 4800);
DISPLAY 0.872340 (-3527 4800);
PAINT GREEN (-3527 4800);
DISPLAY INVISIBLE (-3527 4800);
FORCEADD TAP..1
(-3525 4600);
FORCEPROP 3 LASTPIN (-3575 4600) SIG_NAME M_C_CPU0_SA_DQS_DN<6>
J 0
(-3565 4610);
DISPLAY 0.659574 (-3565 4610);
PAINT MONO (-3565 4610);
DISPLAY INVISIBLE (-3565 4610);
FORCEPROP 1 LASTPIN (-3575 4600) BN 6
J 0
(-3587 4608);
DISPLAY 0.489362 (-3587 4608);
PAINT GREEN (-3587 4608);
FORCEPROP 2 LAST CDS_LIB mstr_standard
J 0
(-3525 4600);
DISPLAY 0.723404 (-3525 4600);
PAINT MONO (-3525 4600);
DISPLAY INVISIBLE (-3525 4600);
FORCEPROP 1 LAST BODY_TYPE PLUMBING
J 0
(-3525 4650);
DISPLAY 0.872340 (-3525 4650);
PAINT GREEN (-3525 4650);
DISPLAY INVISIBLE (-3525 4650);
FORCEPROP 1 LAST HDL_TAP TRUE
J 0
(-3200 4475);
DISPLAY 0.872340 (-3200 4475);
DISPLAY INVISIBLE (-3200 4475);
FORCEPROP 1 LAST PATH I374
J 0
(-3527 4600);
DISPLAY 0.872340 (-3527 4600);
PAINT GREEN (-3527 4600);
DISPLAY INVISIBLE (-3527 4600);
FORCEADD TAP..1
(-3525 4500);
FORCEPROP 3 LASTPIN (-3575 4500) SIG_NAME M_C_CPU0_SA_DQS_DN<5>
J 0
(-3565 4510);
DISPLAY 0.659574 (-3565 4510);
PAINT MONO (-3565 4510);
DISPLAY INVISIBLE (-3565 4510);
FORCEPROP 1 LASTPIN (-3575 4500) BN 5
J 0
(-3587 4508);
DISPLAY 0.489362 (-3587 4508);
PAINT GREEN (-3587 4508);
FORCEPROP 2 LAST CDS_LIB mstr_standard
J 0
(-3525 4500);
DISPLAY 0.723404 (-3525 4500);
PAINT MONO (-3525 4500);
DISPLAY INVISIBLE (-3525 4500);
FORCEPROP 1 LAST BODY_TYPE PLUMBING
J 0
(-3525 4550);
DISPLAY 0.872340 (-3525 4550);
PAINT GREEN (-3525 4550);
DISPLAY INVISIBLE (-3525 4550);
FORCEPROP 1 LAST HDL_TAP TRUE
J 0
(-3200 4375);
DISPLAY 0.872340 (-3200 4375);
DISPLAY INVISIBLE (-3200 4375);
FORCEPROP 1 LAST PATH I375
J 0
(-3527 4500);
DISPLAY 0.872340 (-3527 4500);
PAINT GREEN (-3527 4500);
DISPLAY INVISIBLE (-3527 4500);
FORCEADD TAP..1
(-3525 4400);
FORCEPROP 3 LASTPIN (-3575 4400) SIG_NAME M_C_CPU0_SA_DQS_DN<4>
J 0
(-3565 4410);
DISPLAY 0.659574 (-3565 4410);
PAINT MONO (-3565 4410);
DISPLAY INVISIBLE (-3565 4410);
FORCEPROP 1 LASTPIN (-3575 4400) BN 4
J 0
(-3587 4408);
DISPLAY 0.489362 (-3587 4408);
PAINT GREEN (-3587 4408);
FORCEPROP 2 LAST CDS_LIB mstr_standard
J 0
(-3525 4400);
DISPLAY 0.723404 (-3525 4400);
PAINT MONO (-3525 4400);
DISPLAY INVISIBLE (-3525 4400);
FORCEPROP 1 LAST BODY_TYPE PLUMBING
J 0
(-3525 4450);
DISPLAY 0.872340 (-3525 4450);
PAINT GREEN (-3525 4450);
DISPLAY INVISIBLE (-3525 4450);
FORCEPROP 1 LAST HDL_TAP TRUE
J 0
(-3200 4275);
DISPLAY 0.872340 (-3200 4275);
DISPLAY INVISIBLE (-3200 4275);
FORCEPROP 1 LAST PATH I376
J 0
(-3527 4400);
DISPLAY 0.872340 (-3527 4400);
PAINT GREEN (-3527 4400);
DISPLAY INVISIBLE (-3527 4400);
FORCEADD TAP..1
(-3525 4300);
FORCEPROP 3 LASTPIN (-3575 4300) SIG_NAME M_C_CPU0_SA_DQS_DN<3>
J 0
(-3565 4310);
DISPLAY 0.659574 (-3565 4310);
PAINT MONO (-3565 4310);
DISPLAY INVISIBLE (-3565 4310);
FORCEPROP 1 LASTPIN (-3575 4300) BN 3
J 0
(-3587 4308);
DISPLAY 0.489362 (-3587 4308);
PAINT GREEN (-3587 4308);
FORCEPROP 2 LAST CDS_LIB mstr_standard
J 0
(-3525 4300);
DISPLAY 0.723404 (-3525 4300);
PAINT MONO (-3525 4300);
DISPLAY INVISIBLE (-3525 4300);
FORCEPROP 1 LAST BODY_TYPE PLUMBING
J 0
(-3525 4350);
DISPLAY 0.872340 (-3525 4350);
PAINT GREEN (-3525 4350);
DISPLAY INVISIBLE (-3525 4350);
FORCEPROP 1 LAST HDL_TAP TRUE
J 0
(-3200 4175);
DISPLAY 0.872340 (-3200 4175);
DISPLAY INVISIBLE (-3200 4175);
FORCEPROP 1 LAST PATH I377
J 0
(-3527 4300);
DISPLAY 0.872340 (-3527 4300);
PAINT GREEN (-3527 4300);
DISPLAY INVISIBLE (-3527 4300);
FORCEADD TAP..1
(-3525 4200);
FORCEPROP 3 LASTPIN (-3575 4200) SIG_NAME M_C_CPU0_SA_DQS_DN<2>
J 0
(-3565 4210);
DISPLAY 0.659574 (-3565 4210);
PAINT MONO (-3565 4210);
DISPLAY INVISIBLE (-3565 4210);
FORCEPROP 1 LASTPIN (-3575 4200) BN 2
J 0
(-3587 4208);
DISPLAY 0.489362 (-3587 4208);
PAINT GREEN (-3587 4208);
FORCEPROP 2 LAST CDS_LIB mstr_standard
J 0
(-3525 4200);
DISPLAY 0.723404 (-3525 4200);
PAINT MONO (-3525 4200);
DISPLAY INVISIBLE (-3525 4200);
FORCEPROP 1 LAST BODY_TYPE PLUMBING
J 0
(-3525 4250);
DISPLAY 0.872340 (-3525 4250);
PAINT GREEN (-3525 4250);
DISPLAY INVISIBLE (-3525 4250);
FORCEPROP 1 LAST HDL_TAP TRUE
J 0
(-3200 4075);
DISPLAY 0.872340 (-3200 4075);
DISPLAY INVISIBLE (-3200 4075);
FORCEPROP 1 LAST PATH I378
J 0
(-3527 4200);
DISPLAY 0.872340 (-3527 4200);
PAINT GREEN (-3527 4200);
DISPLAY INVISIBLE (-3527 4200);
FORCEADD TAP..1
(-3525 4100);
FORCEPROP 3 LASTPIN (-3575 4100) SIG_NAME M_C_CPU0_SA_DQS_DN<1>
J 0
(-3565 4110);
DISPLAY 0.659574 (-3565 4110);
PAINT MONO (-3565 4110);
DISPLAY INVISIBLE (-3565 4110);
FORCEPROP 1 LASTPIN (-3575 4100) BN 1
J 0
(-3587 4108);
DISPLAY 0.489362 (-3587 4108);
PAINT GREEN (-3587 4108);
FORCEPROP 2 LAST CDS_LIB mstr_standard
J 0
(-3525 4100);
DISPLAY 0.723404 (-3525 4100);
PAINT MONO (-3525 4100);
DISPLAY INVISIBLE (-3525 4100);
FORCEPROP 1 LAST BODY_TYPE PLUMBING
J 0
(-3525 4150);
DISPLAY 0.872340 (-3525 4150);
PAINT GREEN (-3525 4150);
DISPLAY INVISIBLE (-3525 4150);
FORCEPROP 1 LAST HDL_TAP TRUE
J 0
(-3200 3975);
DISPLAY 0.872340 (-3200 3975);
DISPLAY INVISIBLE (-3200 3975);
FORCEPROP 1 LAST PATH I379
J 0
(-3527 4100);
DISPLAY 0.872340 (-3527 4100);
PAINT GREEN (-3527 4100);
DISPLAY INVISIBLE (-3527 4100);
FORCEADD TAP..1
(-3525 4000);
FORCEPROP 3 LASTPIN (-3575 4000) SIG_NAME M_C_CPU0_SA_DQS_DN<0>
J 0
(-3565 4010);
DISPLAY 0.659574 (-3565 4010);
PAINT MONO (-3565 4010);
DISPLAY INVISIBLE (-3565 4010);
FORCEPROP 1 LASTPIN (-3575 4000) BN 0
J 0
(-3587 4008);
DISPLAY 0.489362 (-3587 4008);
PAINT GREEN (-3587 4008);
FORCEPROP 2 LAST CDS_LIB mstr_standard
J 0
(-3525 4000);
DISPLAY 0.723404 (-3525 4000);
PAINT MONO (-3525 4000);
DISPLAY INVISIBLE (-3525 4000);
FORCEPROP 1 LAST BODY_TYPE PLUMBING
J 0
(-3525 4050);
DISPLAY 0.872340 (-3525 4050);
PAINT GREEN (-3525 4050);
DISPLAY INVISIBLE (-3525 4050);
FORCEPROP 1 LAST HDL_TAP TRUE
J 0
(-3200 3875);
DISPLAY 0.872340 (-3200 3875);
DISPLAY INVISIBLE (-3200 3875);
FORCEPROP 1 LAST PATH I380
J 0
(-3527 4000);
DISPLAY 0.872340 (-3527 4000);
PAINT GREEN (-3527 4000);
DISPLAY INVISIBLE (-3527 4000);
FORCEADD TAP..1
(-3525 3850);
FORCEPROP 3 LASTPIN (-3575 3850) SIG_NAME M_C_CPU0_SB_DQS_DN<9>
J 0
(-3565 3860);
DISPLAY 0.659574 (-3565 3860);
PAINT MONO (-3565 3860);
DISPLAY INVISIBLE (-3565 3860);
FORCEPROP 1 LASTPIN (-3575 3850) BN 9
J 0
(-3587 3858);
DISPLAY 0.489362 (-3587 3858);
PAINT GREEN (-3587 3858);
FORCEPROP 2 LAST CDS_LIB mstr_standard
J 0
(-3525 3850);
DISPLAY 0.723404 (-3525 3850);
PAINT MONO (-3525 3850);
DISPLAY INVISIBLE (-3525 3850);
FORCEPROP 1 LAST BODY_TYPE PLUMBING
J 0
(-3525 3900);
DISPLAY 0.872340 (-3525 3900);
PAINT GREEN (-3525 3900);
DISPLAY INVISIBLE (-3525 3900);
FORCEPROP 1 LAST HDL_TAP TRUE
J 0
(-3200 3725);
DISPLAY 0.872340 (-3200 3725);
DISPLAY INVISIBLE (-3200 3725);
FORCEPROP 1 LAST PATH I381
J 0
(-3527 3850);
DISPLAY 0.872340 (-3527 3850);
PAINT GREEN (-3527 3850);
DISPLAY INVISIBLE (-3527 3850);
FORCEADD TAP..1
(-3525 3750);
FORCEPROP 3 LASTPIN (-3575 3750) SIG_NAME M_C_CPU0_SB_DQS_DN<8>
J 0
(-3565 3760);
DISPLAY 0.659574 (-3565 3760);
PAINT MONO (-3565 3760);
DISPLAY INVISIBLE (-3565 3760);
FORCEPROP 1 LASTPIN (-3575 3750) BN 8
J 0
(-3587 3758);
DISPLAY 0.489362 (-3587 3758);
PAINT GREEN (-3587 3758);
FORCEPROP 2 LAST CDS_LIB mstr_standard
J 0
(-3525 3750);
DISPLAY 0.723404 (-3525 3750);
PAINT MONO (-3525 3750);
DISPLAY INVISIBLE (-3525 3750);
FORCEPROP 1 LAST BODY_TYPE PLUMBING
J 0
(-3525 3800);
DISPLAY 0.872340 (-3525 3800);
PAINT GREEN (-3525 3800);
DISPLAY INVISIBLE (-3525 3800);
FORCEPROP 1 LAST HDL_TAP TRUE
J 0
(-3200 3625);
DISPLAY 0.872340 (-3200 3625);
DISPLAY INVISIBLE (-3200 3625);
FORCEPROP 1 LAST PATH I382
J 0
(-3527 3750);
DISPLAY 0.872340 (-3527 3750);
PAINT GREEN (-3527 3750);
DISPLAY INVISIBLE (-3527 3750);
FORCEADD TAP..1
(-3525 3550);
FORCEPROP 3 LASTPIN (-3575 3550) SIG_NAME M_C_CPU0_SB_DQS_DN<6>
J 0
(-3565 3560);
DISPLAY 0.659574 (-3565 3560);
PAINT MONO (-3565 3560);
DISPLAY INVISIBLE (-3565 3560);
FORCEPROP 1 LASTPIN (-3575 3550) BN 6
J 0
(-3587 3558);
DISPLAY 0.489362 (-3587 3558);
PAINT GREEN (-3587 3558);
FORCEPROP 2 LAST CDS_LIB mstr_standard
J 0
(-3525 3550);
DISPLAY 0.723404 (-3525 3550);
PAINT MONO (-3525 3550);
DISPLAY INVISIBLE (-3525 3550);
FORCEPROP 1 LAST BODY_TYPE PLUMBING
J 0
(-3525 3600);
DISPLAY 0.872340 (-3525 3600);
PAINT GREEN (-3525 3600);
DISPLAY INVISIBLE (-3525 3600);
FORCEPROP 1 LAST HDL_TAP TRUE
J 0
(-3200 3425);
DISPLAY 0.872340 (-3200 3425);
DISPLAY INVISIBLE (-3200 3425);
FORCEPROP 1 LAST PATH I383
J 0
(-3527 3550);
DISPLAY 0.872340 (-3527 3550);
PAINT GREEN (-3527 3550);
DISPLAY INVISIBLE (-3527 3550);
FORCEADD TAP..1
(-3525 3650);
FORCEPROP 3 LASTPIN (-3575 3650) SIG_NAME M_C_CPU0_SB_DQS_DN<7>
J 0
(-3565 3660);
DISPLAY 0.659574 (-3565 3660);
PAINT MONO (-3565 3660);
DISPLAY INVISIBLE (-3565 3660);
FORCEPROP 1 LASTPIN (-3575 3650) BN 7
J 0
(-3587 3658);
DISPLAY 0.489362 (-3587 3658);
PAINT GREEN (-3587 3658);
FORCEPROP 2 LAST CDS_LIB mstr_standard
J 0
(-3525 3650);
DISPLAY 0.723404 (-3525 3650);
PAINT MONO (-3525 3650);
DISPLAY INVISIBLE (-3525 3650);
FORCEPROP 1 LAST BODY_TYPE PLUMBING
J 0
(-3525 3700);
DISPLAY 0.872340 (-3525 3700);
PAINT GREEN (-3525 3700);
DISPLAY INVISIBLE (-3525 3700);
FORCEPROP 1 LAST HDL_TAP TRUE
J 0
(-3200 3525);
DISPLAY 0.872340 (-3200 3525);
DISPLAY INVISIBLE (-3200 3525);
FORCEPROP 1 LAST PATH I384
J 0
(-3527 3650);
DISPLAY 0.872340 (-3527 3650);
PAINT GREEN (-3527 3650);
DISPLAY INVISIBLE (-3527 3650);
FORCEADD TAP..1
(-3525 3450);
FORCEPROP 3 LASTPIN (-3575 3450) SIG_NAME M_C_CPU0_SB_DQS_DN<5>
J 0
(-3565 3460);
DISPLAY 0.659574 (-3565 3460);
PAINT MONO (-3565 3460);
DISPLAY INVISIBLE (-3565 3460);
FORCEPROP 1 LASTPIN (-3575 3450) BN 5
J 0
(-3587 3458);
DISPLAY 0.489362 (-3587 3458);
PAINT GREEN (-3587 3458);
FORCEPROP 2 LAST CDS_LIB mstr_standard
J 0
(-3525 3450);
DISPLAY 0.723404 (-3525 3450);
PAINT MONO (-3525 3450);
DISPLAY INVISIBLE (-3525 3450);
FORCEPROP 1 LAST BODY_TYPE PLUMBING
J 0
(-3525 3500);
DISPLAY 0.872340 (-3525 3500);
PAINT GREEN (-3525 3500);
DISPLAY INVISIBLE (-3525 3500);
FORCEPROP 1 LAST HDL_TAP TRUE
J 0
(-3200 3325);
DISPLAY 0.872340 (-3200 3325);
DISPLAY INVISIBLE (-3200 3325);
FORCEPROP 1 LAST PATH I385
J 0
(-3527 3450);
DISPLAY 0.872340 (-3527 3450);
PAINT GREEN (-3527 3450);
DISPLAY INVISIBLE (-3527 3450);
FORCEADD TAP..1
(-3525 3350);
FORCEPROP 3 LASTPIN (-3575 3350) SIG_NAME M_C_CPU0_SB_DQS_DN<4>
J 0
(-3565 3360);
DISPLAY 0.659574 (-3565 3360);
PAINT MONO (-3565 3360);
DISPLAY INVISIBLE (-3565 3360);
FORCEPROP 1 LASTPIN (-3575 3350) BN 4
J 0
(-3587 3358);
DISPLAY 0.489362 (-3587 3358);
PAINT GREEN (-3587 3358);
FORCEPROP 2 LAST CDS_LIB mstr_standard
J 0
(-3525 3350);
DISPLAY 0.723404 (-3525 3350);
PAINT MONO (-3525 3350);
DISPLAY INVISIBLE (-3525 3350);
FORCEPROP 1 LAST BODY_TYPE PLUMBING
J 0
(-3525 3400);
DISPLAY 0.872340 (-3525 3400);
PAINT GREEN (-3525 3400);
DISPLAY INVISIBLE (-3525 3400);
FORCEPROP 1 LAST HDL_TAP TRUE
J 0
(-3200 3225);
DISPLAY 0.872340 (-3200 3225);
DISPLAY INVISIBLE (-3200 3225);
FORCEPROP 1 LAST PATH I386
J 0
(-3527 3350);
DISPLAY 0.872340 (-3527 3350);
PAINT GREEN (-3527 3350);
DISPLAY INVISIBLE (-3527 3350);
FORCEADD TAP..1
(-3525 3150);
FORCEPROP 3 LASTPIN (-3575 3150) SIG_NAME M_C_CPU0_SB_DQS_DN<2>
J 0
(-3565 3160);
DISPLAY 0.659574 (-3565 3160);
PAINT MONO (-3565 3160);
DISPLAY INVISIBLE (-3565 3160);
FORCEPROP 1 LASTPIN (-3575 3150) BN 2
J 0
(-3587 3158);
DISPLAY 0.489362 (-3587 3158);
PAINT GREEN (-3587 3158);
FORCEPROP 2 LAST CDS_LIB mstr_standard
J 0
(-3525 3150);
DISPLAY 0.723404 (-3525 3150);
PAINT MONO (-3525 3150);
DISPLAY INVISIBLE (-3525 3150);
FORCEPROP 1 LAST BODY_TYPE PLUMBING
J 0
(-3525 3200);
DISPLAY 0.872340 (-3525 3200);
PAINT GREEN (-3525 3200);
DISPLAY INVISIBLE (-3525 3200);
FORCEPROP 1 LAST HDL_TAP TRUE
J 0
(-3200 3025);
DISPLAY 0.872340 (-3200 3025);
DISPLAY INVISIBLE (-3200 3025);
FORCEPROP 1 LAST PATH I387
J 0
(-3527 3150);
DISPLAY 0.872340 (-3527 3150);
PAINT GREEN (-3527 3150);
DISPLAY INVISIBLE (-3527 3150);
FORCEADD TAP..1
(-3525 3250);
FORCEPROP 3 LASTPIN (-3575 3250) SIG_NAME M_C_CPU0_SB_DQS_DN<3>
J 0
(-3565 3260);
DISPLAY 0.659574 (-3565 3260);
PAINT MONO (-3565 3260);
DISPLAY INVISIBLE (-3565 3260);
FORCEPROP 1 LASTPIN (-3575 3250) BN 3
J 0
(-3587 3258);
DISPLAY 0.489362 (-3587 3258);
PAINT GREEN (-3587 3258);
FORCEPROP 2 LAST CDS_LIB mstr_standard
J 0
(-3525 3250);
DISPLAY 0.723404 (-3525 3250);
PAINT MONO (-3525 3250);
DISPLAY INVISIBLE (-3525 3250);
FORCEPROP 1 LAST BODY_TYPE PLUMBING
J 0
(-3525 3300);
DISPLAY 0.872340 (-3525 3300);
PAINT GREEN (-3525 3300);
DISPLAY INVISIBLE (-3525 3300);
FORCEPROP 1 LAST HDL_TAP TRUE
J 0
(-3200 3125);
DISPLAY 0.872340 (-3200 3125);
DISPLAY INVISIBLE (-3200 3125);
FORCEPROP 1 LAST PATH I388
J 0
(-3527 3250);
DISPLAY 0.872340 (-3527 3250);
PAINT GREEN (-3527 3250);
DISPLAY INVISIBLE (-3527 3250);
FORCEADD TAP..1
(-3525 3050);
FORCEPROP 3 LASTPIN (-3575 3050) SIG_NAME M_C_CPU0_SB_DQS_DN<1>
J 0
(-3565 3060);
DISPLAY 0.659574 (-3565 3060);
PAINT MONO (-3565 3060);
DISPLAY INVISIBLE (-3565 3060);
FORCEPROP 1 LASTPIN (-3575 3050) BN 1
J 0
(-3587 3058);
DISPLAY 0.489362 (-3587 3058);
PAINT GREEN (-3587 3058);
FORCEPROP 2 LAST CDS_LIB mstr_standard
J 0
(-3525 3050);
DISPLAY 0.723404 (-3525 3050);
PAINT MONO (-3525 3050);
DISPLAY INVISIBLE (-3525 3050);
FORCEPROP 1 LAST BODY_TYPE PLUMBING
J 0
(-3525 3100);
DISPLAY 0.872340 (-3525 3100);
PAINT GREEN (-3525 3100);
DISPLAY INVISIBLE (-3525 3100);
FORCEPROP 1 LAST HDL_TAP TRUE
J 0
(-3200 2925);
DISPLAY 0.872340 (-3200 2925);
DISPLAY INVISIBLE (-3200 2925);
FORCEPROP 1 LAST PATH I389
J 0
(-3527 3050);
DISPLAY 0.872340 (-3527 3050);
PAINT GREEN (-3527 3050);
DISPLAY INVISIBLE (-3527 3050);
FORCEADD TAP..1
(-3525 2950);
FORCEPROP 3 LASTPIN (-3575 2950) SIG_NAME M_C_CPU0_SB_DQS_DN<0>
J 0
(-3565 2960);
DISPLAY 0.659574 (-3565 2960);
PAINT MONO (-3565 2960);
DISPLAY INVISIBLE (-3565 2960);
FORCEPROP 1 LASTPIN (-3575 2950) BN 0
J 0
(-3587 2958);
DISPLAY 0.489362 (-3587 2958);
PAINT GREEN (-3587 2958);
FORCEPROP 2 LAST CDS_LIB mstr_standard
J 0
(-3525 2950);
DISPLAY 0.723404 (-3525 2950);
PAINT MONO (-3525 2950);
DISPLAY INVISIBLE (-3525 2950);
FORCEPROP 1 LAST BODY_TYPE PLUMBING
J 0
(-3525 3000);
DISPLAY 0.872340 (-3525 3000);
PAINT GREEN (-3525 3000);
DISPLAY INVISIBLE (-3525 3000);
FORCEPROP 1 LAST HDL_TAP TRUE
J 0
(-3200 2825);
DISPLAY 0.872340 (-3200 2825);
DISPLAY INVISIBLE (-3200 2825);
FORCEPROP 1 LAST PATH I390
J 0
(-3527 2950);
DISPLAY 0.872340 (-3527 2950);
PAINT GREEN (-3527 2950);
DISPLAY INVISIBLE (-3527 2950);
FORCEADD TAP..1
(-3725 4950);
FORCEPROP 3 LASTPIN (-3775 4950) SIG_NAME M_C_CPU0_SA_DQS_DP<9>
J 0
(-3765 4960);
DISPLAY 0.659574 (-3765 4960);
PAINT MONO (-3765 4960);
DISPLAY INVISIBLE (-3765 4960);
FORCEPROP 1 LASTPIN (-3775 4950) BN 9
J 0
(-3787 4958);
DISPLAY 0.489362 (-3787 4958);
PAINT GREEN (-3787 4958);
FORCEPROP 2 LAST CDS_LIB mstr_standard
J 0
(-3725 4950);
DISPLAY 0.723404 (-3725 4950);
PAINT MONO (-3725 4950);
DISPLAY INVISIBLE (-3725 4950);
FORCEPROP 1 LAST BODY_TYPE PLUMBING
J 0
(-3725 5000);
DISPLAY 0.872340 (-3725 5000);
PAINT GREEN (-3725 5000);
DISPLAY INVISIBLE (-3725 5000);
FORCEPROP 1 LAST HDL_TAP TRUE
J 0
(-3400 4825);
DISPLAY 0.872340 (-3400 4825);
DISPLAY INVISIBLE (-3400 4825);
FORCEPROP 1 LAST PATH I391
J 0
(-3727 4950);
DISPLAY 0.872340 (-3727 4950);
PAINT GREEN (-3727 4950);
DISPLAY INVISIBLE (-3727 4950);
FORCEADD TAP..1
(-3725 4850);
FORCEPROP 3 LASTPIN (-3775 4850) SIG_NAME M_C_CPU0_SA_DQS_DP<8>
J 0
(-3765 4860);
DISPLAY 0.659574 (-3765 4860);
PAINT MONO (-3765 4860);
DISPLAY INVISIBLE (-3765 4860);
FORCEPROP 1 LASTPIN (-3775 4850) BN 8
J 0
(-3787 4858);
DISPLAY 0.489362 (-3787 4858);
PAINT GREEN (-3787 4858);
FORCEPROP 2 LAST CDS_LIB mstr_standard
J 0
(-3725 4850);
DISPLAY 0.723404 (-3725 4850);
PAINT MONO (-3725 4850);
DISPLAY INVISIBLE (-3725 4850);
FORCEPROP 1 LAST BODY_TYPE PLUMBING
J 0
(-3725 4900);
DISPLAY 0.872340 (-3725 4900);
PAINT GREEN (-3725 4900);
DISPLAY INVISIBLE (-3725 4900);
FORCEPROP 1 LAST HDL_TAP TRUE
J 0
(-3400 4725);
DISPLAY 0.872340 (-3400 4725);
DISPLAY INVISIBLE (-3400 4725);
FORCEPROP 1 LAST PATH I392
J 0
(-3727 4850);
DISPLAY 0.872340 (-3727 4850);
PAINT GREEN (-3727 4850);
DISPLAY INVISIBLE (-3727 4850);
FORCEADD TAP..1
(-3725 4750);
FORCEPROP 3 LASTPIN (-3775 4750) SIG_NAME M_C_CPU0_SA_DQS_DP<7>
J 0
(-3765 4760);
DISPLAY 0.659574 (-3765 4760);
PAINT MONO (-3765 4760);
DISPLAY INVISIBLE (-3765 4760);
FORCEPROP 1 LASTPIN (-3775 4750) BN 7
J 0
(-3787 4758);
DISPLAY 0.489362 (-3787 4758);
PAINT GREEN (-3787 4758);
FORCEPROP 2 LAST CDS_LIB mstr_standard
J 0
(-3725 4750);
DISPLAY 0.723404 (-3725 4750);
PAINT MONO (-3725 4750);
DISPLAY INVISIBLE (-3725 4750);
FORCEPROP 1 LAST BODY_TYPE PLUMBING
J 0
(-3725 4800);
DISPLAY 0.872340 (-3725 4800);
PAINT GREEN (-3725 4800);
DISPLAY INVISIBLE (-3725 4800);
FORCEPROP 1 LAST HDL_TAP TRUE
J 0
(-3400 4625);
DISPLAY 0.872340 (-3400 4625);
DISPLAY INVISIBLE (-3400 4625);
FORCEPROP 1 LAST PATH I393
J 0
(-3727 4750);
DISPLAY 0.872340 (-3727 4750);
PAINT GREEN (-3727 4750);
DISPLAY INVISIBLE (-3727 4750);
FORCEADD TAP..1
(-3725 4550);
FORCEPROP 3 LASTPIN (-3775 4550) SIG_NAME M_C_CPU0_SA_DQS_DP<5>
J 0
(-3765 4560);
DISPLAY 0.659574 (-3765 4560);
PAINT MONO (-3765 4560);
DISPLAY INVISIBLE (-3765 4560);
FORCEPROP 1 LASTPIN (-3775 4550) BN 5
J 0
(-3787 4558);
DISPLAY 0.489362 (-3787 4558);
PAINT GREEN (-3787 4558);
FORCEPROP 2 LAST CDS_LIB mstr_standard
J 0
(-3725 4550);
DISPLAY 0.723404 (-3725 4550);
PAINT MONO (-3725 4550);
DISPLAY INVISIBLE (-3725 4550);
FORCEPROP 1 LAST BODY_TYPE PLUMBING
J 0
(-3725 4600);
DISPLAY 0.872340 (-3725 4600);
PAINT GREEN (-3725 4600);
DISPLAY INVISIBLE (-3725 4600);
FORCEPROP 1 LAST HDL_TAP TRUE
J 0
(-3400 4425);
DISPLAY 0.872340 (-3400 4425);
DISPLAY INVISIBLE (-3400 4425);
FORCEPROP 1 LAST PATH I394
J 0
(-3727 4550);
DISPLAY 0.872340 (-3727 4550);
PAINT GREEN (-3727 4550);
DISPLAY INVISIBLE (-3727 4550);
FORCEADD TAP..1
(-3725 4650);
FORCEPROP 3 LASTPIN (-3775 4650) SIG_NAME M_C_CPU0_SA_DQS_DP<6>
J 0
(-3765 4660);
DISPLAY 0.659574 (-3765 4660);
PAINT MONO (-3765 4660);
DISPLAY INVISIBLE (-3765 4660);
FORCEPROP 1 LASTPIN (-3775 4650) BN 6
J 0
(-3787 4658);
DISPLAY 0.489362 (-3787 4658);
PAINT GREEN (-3787 4658);
FORCEPROP 2 LAST CDS_LIB mstr_standard
J 0
(-3725 4650);
DISPLAY 0.723404 (-3725 4650);
PAINT MONO (-3725 4650);
DISPLAY INVISIBLE (-3725 4650);
FORCEPROP 1 LAST BODY_TYPE PLUMBING
J 0
(-3725 4700);
DISPLAY 0.872340 (-3725 4700);
PAINT GREEN (-3725 4700);
DISPLAY INVISIBLE (-3725 4700);
FORCEPROP 1 LAST HDL_TAP TRUE
J 0
(-3400 4525);
DISPLAY 0.872340 (-3400 4525);
DISPLAY INVISIBLE (-3400 4525);
FORCEPROP 1 LAST PATH I395
J 0
(-3727 4650);
DISPLAY 0.872340 (-3727 4650);
PAINT GREEN (-3727 4650);
DISPLAY INVISIBLE (-3727 4650);
FORCEADD TAP..1
(-3725 4450);
FORCEPROP 3 LASTPIN (-3775 4450) SIG_NAME M_C_CPU0_SA_DQS_DP<4>
J 0
(-3765 4460);
DISPLAY 0.659574 (-3765 4460);
PAINT MONO (-3765 4460);
DISPLAY INVISIBLE (-3765 4460);
FORCEPROP 1 LASTPIN (-3775 4450) BN 4
J 0
(-3787 4458);
DISPLAY 0.489362 (-3787 4458);
PAINT GREEN (-3787 4458);
FORCEPROP 2 LAST CDS_LIB mstr_standard
J 0
(-3725 4450);
DISPLAY 0.723404 (-3725 4450);
PAINT MONO (-3725 4450);
DISPLAY INVISIBLE (-3725 4450);
FORCEPROP 1 LAST BODY_TYPE PLUMBING
J 0
(-3725 4500);
DISPLAY 0.872340 (-3725 4500);
PAINT GREEN (-3725 4500);
DISPLAY INVISIBLE (-3725 4500);
FORCEPROP 1 LAST HDL_TAP TRUE
J 0
(-3400 4325);
DISPLAY 0.872340 (-3400 4325);
DISPLAY INVISIBLE (-3400 4325);
FORCEPROP 1 LAST PATH I396
J 0
(-3727 4450);
DISPLAY 0.872340 (-3727 4450);
PAINT GREEN (-3727 4450);
DISPLAY INVISIBLE (-3727 4450);
FORCEADD TAP..1
(-3725 4350);
FORCEPROP 3 LASTPIN (-3775 4350) SIG_NAME M_C_CPU0_SA_DQS_DP<3>
J 0
(-3765 4360);
DISPLAY 0.659574 (-3765 4360);
PAINT MONO (-3765 4360);
DISPLAY INVISIBLE (-3765 4360);
FORCEPROP 1 LASTPIN (-3775 4350) BN 3
J 0
(-3787 4358);
DISPLAY 0.489362 (-3787 4358);
PAINT GREEN (-3787 4358);
FORCEPROP 2 LAST CDS_LIB mstr_standard
J 0
(-3725 4350);
DISPLAY 0.723404 (-3725 4350);
PAINT MONO (-3725 4350);
DISPLAY INVISIBLE (-3725 4350);
FORCEPROP 1 LAST BODY_TYPE PLUMBING
J 0
(-3725 4400);
DISPLAY 0.872340 (-3725 4400);
PAINT GREEN (-3725 4400);
DISPLAY INVISIBLE (-3725 4400);
FORCEPROP 1 LAST HDL_TAP TRUE
J 0
(-3400 4225);
DISPLAY 0.872340 (-3400 4225);
DISPLAY INVISIBLE (-3400 4225);
FORCEPROP 1 LAST PATH I397
J 0
(-3727 4350);
DISPLAY 0.872340 (-3727 4350);
PAINT GREEN (-3727 4350);
DISPLAY INVISIBLE (-3727 4350);
FORCEADD TAP..1
(-3725 4250);
FORCEPROP 3 LASTPIN (-3775 4250) SIG_NAME M_C_CPU0_SA_DQS_DP<2>
J 0
(-3765 4260);
DISPLAY 0.659574 (-3765 4260);
PAINT MONO (-3765 4260);
DISPLAY INVISIBLE (-3765 4260);
FORCEPROP 1 LASTPIN (-3775 4250) BN 2
J 0
(-3787 4258);
DISPLAY 0.489362 (-3787 4258);
PAINT GREEN (-3787 4258);
FORCEPROP 2 LAST CDS_LIB mstr_standard
J 0
(-3725 4250);
DISPLAY 0.723404 (-3725 4250);
PAINT MONO (-3725 4250);
DISPLAY INVISIBLE (-3725 4250);
FORCEPROP 1 LAST BODY_TYPE PLUMBING
J 0
(-3725 4300);
DISPLAY 0.872340 (-3725 4300);
PAINT GREEN (-3725 4300);
DISPLAY INVISIBLE (-3725 4300);
FORCEPROP 1 LAST HDL_TAP TRUE
J 0
(-3400 4125);
DISPLAY 0.872340 (-3400 4125);
DISPLAY INVISIBLE (-3400 4125);
FORCEPROP 1 LAST PATH I398
J 0
(-3727 4250);
DISPLAY 0.872340 (-3727 4250);
PAINT GREEN (-3727 4250);
DISPLAY INVISIBLE (-3727 4250);
FORCEADD TAP..1
(-3725 4050);
FORCEPROP 3 LASTPIN (-3775 4050) SIG_NAME M_C_CPU0_SA_DQS_DP<0>
J 0
(-3765 4060);
DISPLAY 0.659574 (-3765 4060);
PAINT MONO (-3765 4060);
DISPLAY INVISIBLE (-3765 4060);
FORCEPROP 1 LASTPIN (-3775 4050) BN 0
J 0
(-3787 4058);
DISPLAY 0.489362 (-3787 4058);
PAINT GREEN (-3787 4058);
FORCEPROP 2 LAST CDS_LIB mstr_standard
J 0
(-3725 4050);
DISPLAY 0.723404 (-3725 4050);
PAINT MONO (-3725 4050);
DISPLAY INVISIBLE (-3725 4050);
FORCEPROP 1 LAST BODY_TYPE PLUMBING
J 0
(-3725 4100);
DISPLAY 0.872340 (-3725 4100);
PAINT GREEN (-3725 4100);
DISPLAY INVISIBLE (-3725 4100);
FORCEPROP 1 LAST HDL_TAP TRUE
J 0
(-3400 3925);
DISPLAY 0.872340 (-3400 3925);
DISPLAY INVISIBLE (-3400 3925);
FORCEPROP 1 LAST PATH I399
J 0
(-3727 4050);
DISPLAY 0.872340 (-3727 4050);
PAINT GREEN (-3727 4050);
DISPLAY INVISIBLE (-3727 4050);
FORCEADD TAP..1
(-3725 4150);
FORCEPROP 3 LASTPIN (-3775 4150) SIG_NAME M_C_CPU0_SA_DQS_DP<1>
J 0
(-3765 4160);
DISPLAY 0.659574 (-3765 4160);
PAINT MONO (-3765 4160);
DISPLAY INVISIBLE (-3765 4160);
FORCEPROP 1 LASTPIN (-3775 4150) BN 1
J 0
(-3787 4158);
DISPLAY 0.489362 (-3787 4158);
PAINT GREEN (-3787 4158);
FORCEPROP 2 LAST CDS_LIB mstr_standard
J 0
(-3725 4150);
DISPLAY 0.723404 (-3725 4150);
PAINT MONO (-3725 4150);
DISPLAY INVISIBLE (-3725 4150);
FORCEPROP 1 LAST BODY_TYPE PLUMBING
J 0
(-3725 4200);
DISPLAY 0.872340 (-3725 4200);
PAINT GREEN (-3725 4200);
DISPLAY INVISIBLE (-3725 4200);
FORCEPROP 1 LAST HDL_TAP TRUE
J 0
(-3400 4025);
DISPLAY 0.872340 (-3400 4025);
DISPLAY INVISIBLE (-3400 4025);
FORCEPROP 1 LAST PATH I400
J 0
(-3727 4150);
DISPLAY 0.872340 (-3727 4150);
PAINT GREEN (-3727 4150);
DISPLAY INVISIBLE (-3727 4150);
FORCEADD TAP..1
(-3725 3800);
FORCEPROP 3 LASTPIN (-3775 3800) SIG_NAME M_C_CPU0_SB_DQS_DP<8>
J 0
(-3765 3810);
DISPLAY 0.659574 (-3765 3810);
PAINT MONO (-3765 3810);
DISPLAY INVISIBLE (-3765 3810);
FORCEPROP 1 LASTPIN (-3775 3800) BN 8
J 0
(-3787 3808);
DISPLAY 0.489362 (-3787 3808);
PAINT GREEN (-3787 3808);
FORCEPROP 2 LAST CDS_LIB mstr_standard
J 0
(-3725 3800);
DISPLAY 0.723404 (-3725 3800);
PAINT MONO (-3725 3800);
DISPLAY INVISIBLE (-3725 3800);
FORCEPROP 1 LAST BODY_TYPE PLUMBING
J 0
(-3725 3850);
DISPLAY 0.872340 (-3725 3850);
PAINT GREEN (-3725 3850);
DISPLAY INVISIBLE (-3725 3850);
FORCEPROP 1 LAST HDL_TAP TRUE
J 0
(-3400 3675);
DISPLAY 0.872340 (-3400 3675);
DISPLAY INVISIBLE (-3400 3675);
FORCEPROP 1 LAST PATH I401
J 0
(-3727 3800);
DISPLAY 0.872340 (-3727 3800);
PAINT GREEN (-3727 3800);
DISPLAY INVISIBLE (-3727 3800);
FORCEADD TAP..1
(-3725 3900);
FORCEPROP 3 LASTPIN (-3775 3900) SIG_NAME M_C_CPU0_SB_DQS_DP<9>
J 0
(-3765 3910);
DISPLAY 0.659574 (-3765 3910);
PAINT MONO (-3765 3910);
DISPLAY INVISIBLE (-3765 3910);
FORCEPROP 1 LASTPIN (-3775 3900) BN 9
J 0
(-3787 3908);
DISPLAY 0.489362 (-3787 3908);
PAINT GREEN (-3787 3908);
FORCEPROP 2 LAST CDS_LIB mstr_standard
J 0
(-3725 3900);
DISPLAY 0.723404 (-3725 3900);
PAINT MONO (-3725 3900);
DISPLAY INVISIBLE (-3725 3900);
FORCEPROP 1 LAST BODY_TYPE PLUMBING
J 0
(-3725 3950);
DISPLAY 0.872340 (-3725 3950);
PAINT GREEN (-3725 3950);
DISPLAY INVISIBLE (-3725 3950);
FORCEPROP 1 LAST HDL_TAP TRUE
J 0
(-3400 3775);
DISPLAY 0.872340 (-3400 3775);
DISPLAY INVISIBLE (-3400 3775);
FORCEPROP 1 LAST PATH I402
J 0
(-3727 3900);
DISPLAY 0.872340 (-3727 3900);
PAINT GREEN (-3727 3900);
DISPLAY INVISIBLE (-3727 3900);
FORCEADD TAP..1
(-3725 3700);
FORCEPROP 3 LASTPIN (-3775 3700) SIG_NAME M_C_CPU0_SB_DQS_DP<7>
J 0
(-3765 3710);
DISPLAY 0.659574 (-3765 3710);
PAINT MONO (-3765 3710);
DISPLAY INVISIBLE (-3765 3710);
FORCEPROP 1 LASTPIN (-3775 3700) BN 7
J 0
(-3787 3708);
DISPLAY 0.489362 (-3787 3708);
PAINT GREEN (-3787 3708);
FORCEPROP 2 LAST CDS_LIB mstr_standard
J 0
(-3725 3700);
DISPLAY 0.723404 (-3725 3700);
PAINT MONO (-3725 3700);
DISPLAY INVISIBLE (-3725 3700);
FORCEPROP 1 LAST BODY_TYPE PLUMBING
J 0
(-3725 3750);
DISPLAY 0.872340 (-3725 3750);
PAINT GREEN (-3725 3750);
DISPLAY INVISIBLE (-3725 3750);
FORCEPROP 1 LAST HDL_TAP TRUE
J 0
(-3400 3575);
DISPLAY 0.872340 (-3400 3575);
DISPLAY INVISIBLE (-3400 3575);
FORCEPROP 1 LAST PATH I403
J 0
(-3727 3700);
DISPLAY 0.872340 (-3727 3700);
PAINT GREEN (-3727 3700);
DISPLAY INVISIBLE (-3727 3700);
FORCEADD TAP..1
(-3725 3600);
FORCEPROP 3 LASTPIN (-3775 3600) SIG_NAME M_C_CPU0_SB_DQS_DP<6>
J 0
(-3765 3610);
DISPLAY 0.659574 (-3765 3610);
PAINT MONO (-3765 3610);
DISPLAY INVISIBLE (-3765 3610);
FORCEPROP 1 LASTPIN (-3775 3600) BN 6
J 0
(-3787 3608);
DISPLAY 0.489362 (-3787 3608);
PAINT GREEN (-3787 3608);
FORCEPROP 2 LAST CDS_LIB mstr_standard
J 0
(-3725 3600);
DISPLAY 0.723404 (-3725 3600);
PAINT MONO (-3725 3600);
DISPLAY INVISIBLE (-3725 3600);
FORCEPROP 1 LAST BODY_TYPE PLUMBING
J 0
(-3725 3650);
DISPLAY 0.872340 (-3725 3650);
PAINT GREEN (-3725 3650);
DISPLAY INVISIBLE (-3725 3650);
FORCEPROP 1 LAST HDL_TAP TRUE
J 0
(-3400 3475);
DISPLAY 0.872340 (-3400 3475);
DISPLAY INVISIBLE (-3400 3475);
FORCEPROP 1 LAST PATH I404
J 0
(-3727 3600);
DISPLAY 0.872340 (-3727 3600);
PAINT GREEN (-3727 3600);
DISPLAY INVISIBLE (-3727 3600);
FORCEADD TAP..1
(-3725 3500);
FORCEPROP 3 LASTPIN (-3775 3500) SIG_NAME M_C_CPU0_SB_DQS_DP<5>
J 0
(-3765 3510);
DISPLAY 0.659574 (-3765 3510);
PAINT MONO (-3765 3510);
DISPLAY INVISIBLE (-3765 3510);
FORCEPROP 1 LASTPIN (-3775 3500) BN 5
J 0
(-3787 3508);
DISPLAY 0.489362 (-3787 3508);
PAINT GREEN (-3787 3508);
FORCEPROP 2 LAST CDS_LIB mstr_standard
J 0
(-3725 3500);
DISPLAY 0.723404 (-3725 3500);
PAINT MONO (-3725 3500);
DISPLAY INVISIBLE (-3725 3500);
FORCEPROP 1 LAST BODY_TYPE PLUMBING
J 0
(-3725 3550);
DISPLAY 0.872340 (-3725 3550);
PAINT GREEN (-3725 3550);
DISPLAY INVISIBLE (-3725 3550);
FORCEPROP 1 LAST HDL_TAP TRUE
J 0
(-3400 3375);
DISPLAY 0.872340 (-3400 3375);
DISPLAY INVISIBLE (-3400 3375);
FORCEPROP 1 LAST PATH I405
J 0
(-3727 3500);
DISPLAY 0.872340 (-3727 3500);
PAINT GREEN (-3727 3500);
DISPLAY INVISIBLE (-3727 3500);
FORCEADD TAP..1
(-3725 3400);
FORCEPROP 3 LASTPIN (-3775 3400) SIG_NAME M_C_CPU0_SB_DQS_DP<4>
J 0
(-3765 3410);
DISPLAY 0.659574 (-3765 3410);
PAINT MONO (-3765 3410);
DISPLAY INVISIBLE (-3765 3410);
FORCEPROP 1 LASTPIN (-3775 3400) BN 4
J 0
(-3787 3408);
DISPLAY 0.489362 (-3787 3408);
PAINT GREEN (-3787 3408);
FORCEPROP 2 LAST CDS_LIB mstr_standard
J 0
(-3725 3400);
DISPLAY 0.723404 (-3725 3400);
PAINT MONO (-3725 3400);
DISPLAY INVISIBLE (-3725 3400);
FORCEPROP 1 LAST BODY_TYPE PLUMBING
J 0
(-3725 3450);
DISPLAY 0.872340 (-3725 3450);
PAINT GREEN (-3725 3450);
DISPLAY INVISIBLE (-3725 3450);
FORCEPROP 1 LAST HDL_TAP TRUE
J 0
(-3400 3275);
DISPLAY 0.872340 (-3400 3275);
DISPLAY INVISIBLE (-3400 3275);
FORCEPROP 1 LAST PATH I406
J 0
(-3727 3400);
DISPLAY 0.872340 (-3727 3400);
PAINT GREEN (-3727 3400);
DISPLAY INVISIBLE (-3727 3400);
FORCEADD TAP..1
(-3725 3300);
FORCEPROP 3 LASTPIN (-3775 3300) SIG_NAME M_C_CPU0_SB_DQS_DP<3>
J 0
(-3765 3310);
DISPLAY 0.659574 (-3765 3310);
PAINT MONO (-3765 3310);
DISPLAY INVISIBLE (-3765 3310);
FORCEPROP 1 LASTPIN (-3775 3300) BN 3
J 0
(-3787 3308);
DISPLAY 0.489362 (-3787 3308);
PAINT GREEN (-3787 3308);
FORCEPROP 2 LAST CDS_LIB mstr_standard
J 0
(-3725 3300);
DISPLAY 0.723404 (-3725 3300);
PAINT MONO (-3725 3300);
DISPLAY INVISIBLE (-3725 3300);
FORCEPROP 1 LAST BODY_TYPE PLUMBING
J 0
(-3725 3350);
DISPLAY 0.872340 (-3725 3350);
PAINT GREEN (-3725 3350);
DISPLAY INVISIBLE (-3725 3350);
FORCEPROP 1 LAST HDL_TAP TRUE
J 0
(-3400 3175);
DISPLAY 0.872340 (-3400 3175);
DISPLAY INVISIBLE (-3400 3175);
FORCEPROP 1 LAST PATH I407
J 0
(-3727 3300);
DISPLAY 0.872340 (-3727 3300);
PAINT GREEN (-3727 3300);
DISPLAY INVISIBLE (-3727 3300);
FORCEADD TAP..1
(-3725 3200);
FORCEPROP 3 LASTPIN (-3775 3200) SIG_NAME M_C_CPU0_SB_DQS_DP<2>
J 0
(-3765 3210);
DISPLAY 0.659574 (-3765 3210);
PAINT MONO (-3765 3210);
DISPLAY INVISIBLE (-3765 3210);
FORCEPROP 1 LASTPIN (-3775 3200) BN 2
J 0
(-3787 3208);
DISPLAY 0.489362 (-3787 3208);
PAINT GREEN (-3787 3208);
FORCEPROP 2 LAST CDS_LIB mstr_standard
J 0
(-3725 3200);
DISPLAY 0.723404 (-3725 3200);
PAINT MONO (-3725 3200);
DISPLAY INVISIBLE (-3725 3200);
FORCEPROP 1 LAST BODY_TYPE PLUMBING
J 0
(-3725 3250);
DISPLAY 0.872340 (-3725 3250);
PAINT GREEN (-3725 3250);
DISPLAY INVISIBLE (-3725 3250);
FORCEPROP 1 LAST HDL_TAP TRUE
J 0
(-3400 3075);
DISPLAY 0.872340 (-3400 3075);
DISPLAY INVISIBLE (-3400 3075);
FORCEPROP 1 LAST PATH I408
J 0
(-3727 3200);
DISPLAY 0.872340 (-3727 3200);
PAINT GREEN (-3727 3200);
DISPLAY INVISIBLE (-3727 3200);
FORCEADD TAP..1
(-3725 3100);
FORCEPROP 3 LASTPIN (-3775 3100) SIG_NAME M_C_CPU0_SB_DQS_DP<1>
J 0
(-3765 3110);
DISPLAY 0.659574 (-3765 3110);
PAINT MONO (-3765 3110);
DISPLAY INVISIBLE (-3765 3110);
FORCEPROP 1 LASTPIN (-3775 3100) BN 1
J 0
(-3787 3108);
DISPLAY 0.489362 (-3787 3108);
PAINT GREEN (-3787 3108);
FORCEPROP 2 LAST CDS_LIB mstr_standard
J 0
(-3725 3100);
DISPLAY 0.723404 (-3725 3100);
PAINT MONO (-3725 3100);
DISPLAY INVISIBLE (-3725 3100);
FORCEPROP 1 LAST BODY_TYPE PLUMBING
J 0
(-3725 3150);
DISPLAY 0.872340 (-3725 3150);
PAINT GREEN (-3725 3150);
DISPLAY INVISIBLE (-3725 3150);
FORCEPROP 1 LAST HDL_TAP TRUE
J 0
(-3400 2975);
DISPLAY 0.872340 (-3400 2975);
DISPLAY INVISIBLE (-3400 2975);
FORCEPROP 1 LAST PATH I409
J 0
(-3727 3100);
DISPLAY 0.872340 (-3727 3100);
PAINT GREEN (-3727 3100);
DISPLAY INVISIBLE (-3727 3100);
FORCEADD TAP..1
(-3725 3000);
FORCEPROP 3 LASTPIN (-3775 3000) SIG_NAME M_C_CPU0_SB_DQS_DP<0>
J 0
(-3765 3010);
DISPLAY 0.659574 (-3765 3010);
PAINT MONO (-3765 3010);
DISPLAY INVISIBLE (-3765 3010);
FORCEPROP 1 LASTPIN (-3775 3000) BN 0
J 0
(-3787 3008);
DISPLAY 0.489362 (-3787 3008);
PAINT GREEN (-3787 3008);
FORCEPROP 2 LAST CDS_LIB mstr_standard
J 0
(-3725 3000);
DISPLAY 0.723404 (-3725 3000);
PAINT MONO (-3725 3000);
DISPLAY INVISIBLE (-3725 3000);
FORCEPROP 1 LAST BODY_TYPE PLUMBING
J 0
(-3725 3050);
DISPLAY 0.872340 (-3725 3050);
PAINT GREEN (-3725 3050);
DISPLAY INVISIBLE (-3725 3050);
FORCEPROP 1 LAST HDL_TAP TRUE
J 0
(-3400 2875);
DISPLAY 0.872340 (-3400 2875);
DISPLAY INVISIBLE (-3400 2875);
FORCEPROP 1 LAST PATH I410
J 0
(-3727 3000);
DISPLAY 0.872340 (-3727 3000);
PAINT GREEN (-3727 3000);
DISPLAY INVISIBLE (-3727 3000);
FORCEADD SCONN288_DDR506112002KQ..2
(-4675 3950);
FORCEPROP 1 LAST LOCATION J17
J 0
(-5275 5275);
DISPLAY 0.468085 (-5275 5275);
PAINT SKYBLUE (-5275 5275);
FORCEPROP 0 LAST $SEC 2
J 0
(-5125 5425);
DISPLAY 0.680851 (-5125 5425);
PAINT MONO (-5125 5425);
DISPLAY INVISIBLE (-5125 5425);
FORCEPROP 0 LAST CDS_SEC 2
J 0
(-5125 5425);
DISPLAY 1.021277 (-5125 5425);
DISPLAY INVISIBLE (-5125 5425);
FORCEPROP 0 LASTPIN (-3925 4000) $PN 12
J 0
(-3915 4010);
DISPLAY 0.680851 (-3915 4010);
PAINT MONO (-3915 4010);
FORCEPROP 0 LASTPIN (-3925 4050) $PN 11
J 0
(-3915 4060);
DISPLAY 0.680851 (-3915 4060);
PAINT MONO (-3915 4060);
FORCEPROP 0 LASTPIN (-3925 2950) $PN 105
J 0
(-3915 2960);
DISPLAY 0.680851 (-3915 2960);
PAINT MONO (-3915 2960);
FORCEPROP 0 LASTPIN (-3925 3000) $PN 104
J 0
(-3915 3010);
DISPLAY 0.680851 (-3915 3010);
PAINT MONO (-3915 3010);
FORCEPROP 0 LASTPIN (-3925 4100) $PN 23
J 0
(-3915 4110);
DISPLAY 0.680851 (-3915 4110);
PAINT MONO (-3915 4110);
FORCEPROP 0 LASTPIN (-3925 4150) $PN 22
J 0
(-3915 4160);
DISPLAY 0.680851 (-3915 4160);
PAINT MONO (-3915 4160);
FORCEPROP 0 LASTPIN (-3925 3050) $PN 116
J 0
(-3915 3060);
DISPLAY 0.680851 (-3915 3060);
PAINT MONO (-3915 3060);
FORCEPROP 0 LASTPIN (-3925 3100) $PN 115
J 0
(-3915 3110);
DISPLAY 0.680851 (-3915 3110);
PAINT MONO (-3915 3110);
FORCEPROP 0 LASTPIN (-3925 4200) $PN 34
J 0
(-3915 4210);
DISPLAY 0.680851 (-3915 4210);
PAINT MONO (-3915 4210);
FORCEPROP 0 LASTPIN (-3925 4250) $PN 33
J 0
(-3915 4260);
DISPLAY 0.680851 (-3915 4260);
PAINT MONO (-3915 4260);
FORCEPROP 0 LASTPIN (-3925 3150) $PN 127
J 0
(-3915 3160);
DISPLAY 0.680851 (-3915 3160);
PAINT MONO (-3915 3160);
FORCEPROP 0 LASTPIN (-3925 3200) $PN 126
J 0
(-3915 3210);
DISPLAY 0.680851 (-3915 3210);
PAINT MONO (-3915 3210);
FORCEPROP 0 LASTPIN (-3925 4300) $PN 45
J 0
(-3915 4310);
DISPLAY 0.680851 (-3915 4310);
PAINT MONO (-3915 4310);
FORCEPROP 0 LASTPIN (-3925 4350) $PN 44
J 0
(-3915 4360);
DISPLAY 0.680851 (-3915 4360);
PAINT MONO (-3915 4360);
FORCEPROP 0 LASTPIN (-3925 3250) $PN 138
J 0
(-3915 3260);
DISPLAY 0.680851 (-3915 3260);
PAINT MONO (-3915 3260);
FORCEPROP 0 LASTPIN (-3925 3300) $PN 137
J 0
(-3915 3310);
DISPLAY 0.680851 (-3915 3310);
PAINT MONO (-3915 3310);
FORCEPROP 0 LASTPIN (-3925 4400) $PN 56
J 0
(-3915 4410);
DISPLAY 0.680851 (-3915 4410);
PAINT MONO (-3915 4410);
FORCEPROP 0 LASTPIN (-3925 4450) $PN 55
J 0
(-3915 4460);
DISPLAY 0.680851 (-3915 4460);
PAINT MONO (-3915 4460);
FORCEPROP 0 LASTPIN (-3925 3350) $PN 238
J 0
(-3915 3360);
DISPLAY 0.680851 (-3915 3360);
PAINT MONO (-3915 3360);
FORCEPROP 0 LASTPIN (-3925 3400) $PN 239
J 0
(-3915 3410);
DISPLAY 0.680851 (-3915 3410);
PAINT MONO (-3915 3410);
FORCEPROP 0 LASTPIN (-3925 4500) $PN 156
J 0
(-3915 4510);
DISPLAY 0.680851 (-3915 4510);
PAINT MONO (-3915 4510);
FORCEPROP 0 LASTPIN (-3925 4550) $PN 157
J 0
(-3915 4560);
DISPLAY 0.680851 (-3915 4560);
PAINT MONO (-3915 4560);
FORCEPROP 0 LASTPIN (-3925 3450) $PN 249
J 0
(-3915 3460);
DISPLAY 0.680851 (-3915 3460);
PAINT MONO (-3915 3460);
FORCEPROP 0 LASTPIN (-3925 3500) $PN 250
J 0
(-3915 3510);
DISPLAY 0.680851 (-3915 3510);
PAINT MONO (-3915 3510);
FORCEPROP 0 LASTPIN (-3925 4600) $PN 167
J 0
(-3915 4610);
DISPLAY 0.680851 (-3915 4610);
PAINT MONO (-3915 4610);
FORCEPROP 0 LASTPIN (-3925 4650) $PN 168
J 0
(-3915 4660);
DISPLAY 0.680851 (-3915 4660);
PAINT MONO (-3915 4660);
FORCEPROP 0 LASTPIN (-3925 3550) $PN 260
J 0
(-3915 3560);
DISPLAY 0.680851 (-3915 3560);
PAINT MONO (-3915 3560);
FORCEPROP 0 LASTPIN (-3925 3600) $PN 261
J 0
(-3915 3610);
DISPLAY 0.680851 (-3915 3610);
PAINT MONO (-3915 3610);
FORCEPROP 0 LASTPIN (-3925 4700) $PN 178
J 0
(-3915 4710);
DISPLAY 0.680851 (-3915 4710);
PAINT MONO (-3915 4710);
FORCEPROP 0 LASTPIN (-3925 4750) $PN 179
J 0
(-3915 4760);
DISPLAY 0.680851 (-3915 4760);
PAINT MONO (-3915 4760);
FORCEPROP 0 LASTPIN (-3925 3650) $PN 271
J 0
(-3915 3660);
DISPLAY 0.680851 (-3915 3660);
PAINT MONO (-3915 3660);
FORCEPROP 0 LASTPIN (-3925 3700) $PN 272
J 0
(-3915 3710);
DISPLAY 0.680851 (-3915 3710);
PAINT MONO (-3915 3710);
FORCEPROP 0 LASTPIN (-3925 4800) $PN 189
J 0
(-3915 4810);
DISPLAY 0.680851 (-3915 4810);
PAINT MONO (-3915 4810);
FORCEPROP 0 LASTPIN (-3925 4850) $PN 190
J 0
(-3915 4860);
DISPLAY 0.680851 (-3915 4860);
PAINT MONO (-3915 4860);
FORCEPROP 0 LASTPIN (-3925 3750) $PN 282
J 0
(-3915 3760);
DISPLAY 0.680851 (-3915 3760);
PAINT MONO (-3915 3760);
FORCEPROP 0 LASTPIN (-3925 3800) $PN 283
J 0
(-3915 3810);
DISPLAY 0.680851 (-3915 3810);
PAINT MONO (-3915 3810);
FORCEPROP 0 LASTPIN (-3925 4900) $PN 200
J 0
(-3915 4910);
DISPLAY 0.680851 (-3915 4910);
PAINT MONO (-3915 4910);
FORCEPROP 0 LASTPIN (-3925 4950) $PN 201
J 0
(-3915 4960);
DISPLAY 0.680851 (-3915 4960);
PAINT MONO (-3915 4960);
FORCEPROP 0 LASTPIN (-3925 3850) $PN 94
J 0
(-3915 3860);
DISPLAY 0.680851 (-3915 3860);
PAINT MONO (-3915 3860);
FORCEPROP 0 LASTPIN (-3925 3900) $PN 93
J 0
(-3915 3910);
DISPLAY 0.680851 (-3915 3910);
PAINT MONO (-3915 3910);
FORCEPROP 1 LAST MATERIAL IO
J 0
(-5275 5125);
DISPLAY 0.468085 (-5275 5125);
PAINT SKYBLUE (-5275 5125);
FORCEPROP 2 LAST PART_TYPE SMLF
J 0
(-5125 5375);
DISPLAY 1.021277 (-5125 5375);
FORCEPROP 2 LAST VALUE SCONN288_DDR506112002KQ
J 0
(-5125 5325);
DISPLAY 0.489362 (-5125 5325);
PAINT SKYBLUE (-5125 5325);
FORCEPROP 1 LAST PART_NUMBER DFHST8FS479
J 0
(-5275 5200);
DISPLAY 0.468085 (-5275 5200);
PAINT SKYBLUE (-5275 5200);
FORCEPROP 1 LAST CDS_LMAN_SYM_OUTLINE -600,1150,600,-1150
J 0
(-4675 3950);
DISPLAY 0.468085 (-4675 3950);
PAINT GREEN (-4675 3950);
DISPLAY INVISIBLE (-4675 3950);
FORCEPROP 1 LAST PATH I411
J 0
(-4675 3950);
DISPLAY 0.723404 (-4675 3950);
PAINT GREEN (-4675 3950);
DISPLAY INVISIBLE (-4675 3950);
FORCEPROP 1 LAST NEEDS_NO_SIZE TRUE
J 0
(-4675 3950);
DISPLAY 0.723404 (-4675 3950);
PAINT GREEN (-4675 3950);
DISPLAY INVISIBLE (-4675 3950);
FORCEPROP 2 LAST CDS_LIB pure_quanta
J 0
(-4675 3950);
DISPLAY INVISIBLE (-4675 3950);
FORCEADD GND..1
(-3000 5800);
FORCEPROP 3 LASTPIN (-3000 5850) SIG_NAME GND\g
J 0
(-2990 5860);
DISPLAY 0.659574 (-2990 5860);
PAINT MONO (-2990 5860);
DISPLAY INVISIBLE (-2990 5860);
FORCEPROP 2 LAST CDS_LIB pure_quanta_power
J 0
(-3000 5800);
DISPLAY INVISIBLE (-3000 5800);
FORCEPROP 2 LAST BOM_COST MEM
J 0
(-2975 5925);
DISPLAY 0.659574 (-2975 5925);
DISPLAY INVISIBLE (-2975 5925);
FORCEPROP 1 LAST SIZE 1B
J 0
(-2925 5750);
DISPLAY 0.723404 (-2925 5750);
PAINT GREEN (-2925 5750);
DISPLAY INVISIBLE (-2925 5750);
FORCEPROP 1 LAST PATH I412
J 0
(-2925 5800);
DISPLAY 0.872340 (-2925 5800);
PAINT AQUA (-2925 5800);
DISPLAY INVISIBLE (-2925 5800);
FORCEPROP 2 LAST ROOM MEM_EFGH_DECOUPLING_CAPS
J 0
(-2975 5875);
DISPLAY 0.659574 (-2975 5875);
PAINT RED (-2975 5875);
DISPLAY INVISIBLE (-2975 5875);
FORCEPROP 1 LAST HDL_POWER GND
J 0
(-3000 5950);
DISPLAY 0.723404 (-3000 5950);
PAINT GREEN (-3000 5950);
DISPLAY INVISIBLE (-3000 5950);
FORCEADD Q_CAP..1
R 2
(-3000 6150);
FORCEPROP 1 LAST LOCATION C146
J 2
(-3050 6250);
DISPLAY 0.489362 (-3050 6250);
PAINT SKYBLUE (-3050 6250);
FORCEPROP 0 LAST $SEC 1
J 0
(-3050 6300);
DISPLAY 0.680851 (-3050 6300);
PAINT MONO (-3050 6300);
DISPLAY INVISIBLE (-3050 6300);
FORCEPROP 0 LAST CDS_SEC 1
J 0
(-3050 6300);
DISPLAY 0.680851 (-3050 6300);
DISPLAY INVISIBLE (-3050 6300);
FORCEPROP 1 LASTPIN (-3000 6250) $PN 1
J 2
(-3010 6230);
DISPLAY 0.489362 (-3010 6230);
PAINT MONO (-3010 6230);
FORCEPROP 1 LASTPIN (-3000 6050) $PN 2
J 2
(-3010 6030);
DISPLAY 0.489362 (-3010 6030);
PAINT MONO (-3010 6030);
FORCEPROP 1 LAST MATERIAL X6S
J 2
(-3050 6050);
DISPLAY 0.489362 (-3050 6050);
PAINT SKYBLUE (-3050 6050);
FORCEPROP 1 LAST TOLERANCE 10%
J 2
(-3050 6100);
DISPLAY 0.489362 (-3050 6100);
PAINT SKYBLUE (-3050 6100);
FORCEPROP 1 LAST VALUE 10UF
J 2
(-3050 6200);
DISPLAY 0.489362 (-3050 6200);
PAINT SKYBLUE (-3050 6200);
FORCEPROP 1 LAST PART_NUMBER CH6104KEA00
J 2
(-3050 6000);
DISPLAY 0.489362 (-3050 6000);
PAINT SKYBLUE (-3050 6000);
FORCEPROP 1 LAST VOLTAGE 25V
J 2
(-3050 6150);
DISPLAY 0.489362 (-3050 6150);
PAINT SKYBLUE (-3050 6150);
FORCEPROP 1 LAST PACK_TYPE C0805
J 2
(-3050 5950);
DISPLAY 0.489362 (-3050 5950);
PAINT SKYBLUE (-3050 5950);
FORCEPROP 0 LAST BOM_COST MEM
J 2
(-3055 6295);
DISPLAY 0.595745 (-3055 6295);
PAINT MONO (-3055 6295);
DISPLAY INVISIBLE (-3055 6295);
FORCEPROP 2 LAST CDS_LIB pure_quanta
J 0
(-3000 6150);
DISPLAY INVISIBLE (-3000 6150);
FORCEPROP 1 LAST PATH I413
J 2
(-3050 6300);
DISPLAY 0.978723 (-3050 6300);
PAINT WHITE (-3050 6300);
DISPLAY INVISIBLE (-3050 6300);
FORCEPROP 0 LAST ROOM MEM_CH_A_CPU0_DIMM1
J 2
(-3055 6295);
DISPLAY 0.595745 (-3055 6295);
PAINT RED (-3055 6295);
DISPLAY INVISIBLE (-3055 6295);
FORCEADD Q_CAP..1
R 2
(-2425 6150);
FORCEPROP 1 LAST LOCATION C147
J 2
(-2475 6250);
DISPLAY 0.489362 (-2475 6250);
PAINT SKYBLUE (-2475 6250);
FORCEPROP 0 LAST $SEC 1
J 0
(-2475 6300);
DISPLAY 0.680851 (-2475 6300);
PAINT MONO (-2475 6300);
DISPLAY INVISIBLE (-2475 6300);
FORCEPROP 0 LAST CDS_SEC 1
J 0
(-2475 6300);
DISPLAY 0.680851 (-2475 6300);
DISPLAY INVISIBLE (-2475 6300);
FORCEPROP 1 LASTPIN (-2425 6250) $PN 1
J 2
(-2435 6230);
DISPLAY 0.489362 (-2435 6230);
PAINT MONO (-2435 6230);
FORCEPROP 1 LASTPIN (-2425 6050) $PN 2
J 2
(-2435 6030);
DISPLAY 0.489362 (-2435 6030);
PAINT MONO (-2435 6030);
FORCEPROP 1 LAST MATERIAL X6S
J 2
(-2475 6050);
DISPLAY 0.489362 (-2475 6050);
PAINT SKYBLUE (-2475 6050);
FORCEPROP 1 LAST TOLERANCE 10%
J 2
(-2475 6100);
DISPLAY 0.489362 (-2475 6100);
PAINT SKYBLUE (-2475 6100);
FORCEPROP 1 LAST VALUE 10UF
J 2
(-2475 6200);
DISPLAY 0.489362 (-2475 6200);
PAINT SKYBLUE (-2475 6200);
FORCEPROP 1 LAST PART_NUMBER CH6104KEA00
J 2
(-2475 6000);
DISPLAY 0.489362 (-2475 6000);
PAINT SKYBLUE (-2475 6000);
FORCEPROP 1 LAST VOLTAGE 25V
J 2
(-2475 6150);
DISPLAY 0.489362 (-2475 6150);
PAINT SKYBLUE (-2475 6150);
FORCEPROP 1 LAST PACK_TYPE C0805
J 2
(-2475 5950);
DISPLAY 0.489362 (-2475 5950);
PAINT SKYBLUE (-2475 5950);
FORCEPROP 0 LAST BOM_COST MEM
J 2
(-2480 6295);
DISPLAY 0.595745 (-2480 6295);
PAINT MONO (-2480 6295);
DISPLAY INVISIBLE (-2480 6295);
FORCEPROP 2 LAST CDS_LIB pure_quanta
J 0
(-2425 6150);
DISPLAY INVISIBLE (-2425 6150);
FORCEPROP 1 LAST PATH I414
J 2
(-2475 6300);
DISPLAY 0.978723 (-2475 6300);
PAINT WHITE (-2475 6300);
DISPLAY INVISIBLE (-2475 6300);
FORCEPROP 0 LAST ROOM MEM_CH_A_CPU0_DIMM1
J 2
(-2480 6295);
DISPLAY 0.595745 (-2480 6295);
PAINT RED (-2480 6295);
DISPLAY INVISIBLE (-2480 6295);
FORCEADD UNIVERSAL_POWER..1
(-3000 6475);
FORCEPROP 3 LASTPIN (-3000 6425) SIG_NAME P12V_MEM_1\g
J 0
(-2990 6435);
DISPLAY 0.659574 (-2990 6435);
PAINT MONO (-2990 6435);
DISPLAY INVISIBLE (-2990 6435);
FORCEPROP 1 LAST HDL_POWER P12V_MEM_1
J 1
(-3025 6525);
DISPLAY 0.489362 (-3025 6525);
PAINT GREEN (-3025 6525);
FORCEPROP 2 LAST BOM_COST VR_SYSTEM
J 0
(-3000 6575);
DISPLAY 0.617021 (-3000 6575);
PAINT PURPLE (-3000 6575);
DISPLAY INVISIBLE (-3000 6575);
FORCEPROP 2 LAST CDS_LIB pure_quanta_power
J 0
(-3000 6475);
DISPLAY INVISIBLE (-3000 6475);
FORCEPROP 1 LAST PATH I415
J 0
(-2950 6500);
DISPLAY 0.872340 (-2950 6500);
PAINT AQUA (-2950 6500);
DISPLAY INVISIBLE (-2950 6500);
FORCEADD OFFPAGE..1
(-8525 3025);
FORCEPROP 2 LAST $XR5 90 
J 0
(-9227 3025);
DISPLAY 0.638298 (-9227 3025);
PAINT MONO (-9227 3025);
FORCEPROP 2 LAST $XR4 89 
J 0
(-9137 3025);
DISPLAY 0.638298 (-9137 3025);
PAINT MONO (-9137 3025);
FORCEPROP 2 LAST $XR3 88 
J 0
(-9047 3025);
DISPLAY 0.638298 (-9047 3025);
PAINT MONO (-9047 3025);
FORCEPROP 2 LAST $XR2 86 
J 0
(-8957 3025);
DISPLAY 0.638298 (-8957 3025);
PAINT MONO (-8957 3025);
FORCEPROP 2 LAST $XR1 85 
J 0
(-8867 3025);
DISPLAY 0.638298 (-8867 3025);
PAINT MONO (-8867 3025);
FORCEPROP 2 LAST $XR0 136 
J 0
(-8777 3025);
DISPLAY 0.638298 (-8777 3025);
PAINT MONO (-8777 3025);
FORCEPROP 2 LAST PATH I416
J 0
(-8800 3075);
DISPLAY 0.680851 (-8800 3075);
DISPLAY INVISIBLE (-8800 3075);
FORCEPROP 1 LAST COMMENT_BODY TRUE
J 0
(-8400 2925);
DISPLAY 0.872340 (-8400 2925);
PAINT GREEN (-8400 2925);
DISPLAY INVISIBLE (-8400 2925);
FORCEPROP 1 LAST OFFPAGE TRUE
J 0
(-8200 2900);
DISPLAY 0.872340 (-8200 2900);
PAINT GREEN (-8200 2900);
DISPLAY INVISIBLE (-8200 2900);
FORCEPROP 2 LAST CDS_LIB mstr_standard
J 0
(-8525 3025);
DISPLAY 0.808511 (-8525 3025);
DISPLAY INVISIBLE (-8525 3025);
FORCEADD Q_RES..1
(-7950 3025);
FORCEPROP 1 LAST $LOCATION R1570
J 0
(-8000 3050);
DISPLAY 0.510638 (-8000 3050);
PAINT SKYBLUE (-8000 3050);
FORCEPROP 0 LAST CDS_LOCATION R1570
J 0
(-8000 3125);
DISPLAY 0.680851 (-8000 3125);
DISPLAY INVISIBLE (-8000 3125);
FORCEPROP 0 LAST $SEC 1
J 0
(-8000 3125);
DISPLAY 0.680851 (-8000 3125);
PAINT MONO (-8000 3125);
DISPLAY INVISIBLE (-8000 3125);
FORCEPROP 0 LAST CDS_SEC 1
J 0
(-8000 3125);
DISPLAY 0.680851 (-8000 3125);
DISPLAY INVISIBLE (-8000 3125);
FORCEPROP 1 LASTPIN (-8050 3025) $PN 1
J 0
(-8038 3037);
DISPLAY 0.787234 (-8038 3037);
PAINT MONO (-8038 3037);
FORCEPROP 1 LASTPIN (-7850 3025) $PN 2
J 0
(-7888 3037);
DISPLAY 0.787234 (-7888 3037);
PAINT MONO (-7888 3037);
FORCEPROP 1 LAST VALUE 49.9
J 2
(-7850 3100);
DISPLAY 0.404255 (-7850 3100);
PAINT SKYBLUE (-7850 3100);
FORCEPROP 2 LAST CDS_LIB pure_quanta
J 0
(-7950 3025);
DISPLAY INVISIBLE (-7950 3025);
FORCEPROP 1 LAST PATH I417
J 0
(-8000 3175);
DISPLAY 0.978723 (-8000 3175);
PAINT WHITE (-8000 3175);
DISPLAY INVISIBLE (-8000 3175);
FORCEPROP 1 LAST MATERIAL CHIP
J 0
(-7950 2875);
DISPLAY 0.978723 (-7950 2875);
DISPLAY INVISIBLE (-7950 2875);
FORCEPROP 1 LAST PACK_TYPE 0402LF
J 0
(-7700 2875);
DISPLAY 0.978723 (-7700 2875);
DISPLAY INVISIBLE (-7700 2875);
FORCEPROP 1 LAST WATTAGE 1/16W
J 2
(-7975 2875);
DISPLAY 0.978723 (-7975 2875);
DISPLAY INVISIBLE (-7975 2875);
FORCEPROP 1 LAST TOLERANCE 1%
J 0
(-7950 2925);
DISPLAY 0.978723 (-7950 2925);
DISPLAY INVISIBLE (-7950 2925);
FORCEPROP 1 LAST PART_NUMBER CS04992FB07
J 0
(-8000 3125);
DISPLAY 0.978723 (-8000 3125);
DISPLAY INVISIBLE (-8000 3125);
FORCEADD QUANTA_TITLE_BLOCK_C..1
(-100 100);
FORCEPROP 0 LAST CDS_CON_LAST_MODIFIED Fri Mar 11 14:52:53 2022
J 0
(-1985 115);
DISPLAY INVISIBLE (-1985 115);
FORCEPROP 1 LAST CUSTOM_TXT_CDS <CON_LAST_MODIFIED>
J 0
(-1985 115);
DISPLAY 0.978723 (-1985 115);
FORCEPROP 2 LAST CUSTOM_TXT_CDS <XR_PAGE_TITLE>
J 0
(-7990 5350);
DISPLAY 0.638298 (-7990 5350);
PAINT PINK (-7990 5350);
DISPLAY INVISIBLE (-7990 5350);
FORCEPROP 1 LAST CUSTOM_TXT_CDS <NAME_2>
J 0
(-3275 150);
FORCEPROP 1 LAST CUSTOM_TXT_CDS <NAME_1>
J 0
(-3275 275);
FORCEPROP 1 LAST CUSTOM_TXT_CDS <Q_NUMBER>
J 0
(-1503 203);
DISPLAY 1.212766 (-1503 203);
FORCEPROP 1 LAST CUSTOM_TXT_CDS <Q_PROJ>
J 0
(-2482 202);
DISPLAY 1.212766 (-2482 202);
FORCEPROP 1 LAST CUSTOM_TXT_CDS <Q_REV>
J 0
(-284 203);
DISPLAY 1.212766 (-284 203);
FORCEPROP 1 LAST CUSTOM_TXT_CDS <CON_PAGE_NUM> OF <CON_TOTAL_PAGES>
J 0
(-546 118);
DISPLAY 0.978723 (-546 118);
FORCEPROP 1 LAST Q_TITLE DDR5 - CPU0 CHC
J 0
(-9425 150);
DISPLAY 2.446809 (-9425 150);
PAINT GREEN (-9425 150);
FORCEPROP 1 LAST Q_DEPT BU9
J 1
(-3863 149);
DISPLAY 1.957447 (-3863 149);
PAINT GREEN (-3863 149);
FORCEPROP 2 LAST CDS_LIB pure_quanta
J 0
(-100 100);
DISPLAY INVISIBLE (-100 100);
FORCEPROP 1 LAST CDS_LMAN_SYM_OUTLINE -9475,6775,100,-125
J 0
(-100 100);
DISPLAY 0.468085 (-100 100);
PAINT GREEN (-100 100);
DISPLAY INVISIBLE (-100 100);
FORCEPROP 2 LAST PAGE_BORDER TRUE
J 0
(-7990 5350);
DISPLAY 0.638298 (-7990 5350);
PAINT PINK (-7990 5350);
DISPLAY INVISIBLE (-7990 5350);
FORCEPROP 1 LAST COMMENT_BODY TRUE
J 0
(-88 87);
DISPLAY 0.978723 (-88 87);
PAINT GREEN (-88 87);
DISPLAY INVISIBLE (-88 87);
FORCEPROP 2 LAST CDS_XR_PAGE_TITLE CR-87 : @T6G_MB_LIB.T6G(SCH_1):PAGE87
J 0
(-7990 5350);
DISPLAY 0.638298 (-7990 5350);
PAINT PINK (-7990 5350);
DISPLAY INVISIBLE (-7990 5350);
FORCEADD DNS..2
(-8525 2625);
PAINT RED (-8525 2625);
FORCEPROP 2 LAST CDS_LIB mstr_misc
J 0
(-8525 2625);
DISPLAY INVISIBLE (-8525 2625);
FORCEPROP 1 LAST COMMENT_BODY TRUE
R 1
J 0
(-8450 2400);
DISPLAY 0.872340 (-8450 2400);
PAINT PEACH (-8450 2400);
DISPLAY INVISIBLE (-8450 2400);
WIRE 17 -1 (-6175 5750)(-6175 5700);
WIRE 17 -1 (-6175 5775)(-6175 5750);
WIRE 17 -1 (-6175 5700)(-6175 5650);
WIRE 17 -1 (-6175 5650)(-6175 5600);
WIRE 17 -1 (-6175 5775)(-5725 5775);
FORCEPROP 2 LAST SIG_NAME M_C_CPU0_SA_DQ<31:0>
J 2
(-5725 5785);
DISPLAY 0.489362 (-5725 5785);
WIRE 17 -1 (-7975 4350)(-7975 4300);
WIRE 17 -1 (-7975 4350)(-7975 4375);
WIRE 17 -1 (-7975 4250)(-7975 4300);
WIRE 17 -1 (-7975 4250)(-7975 4200);
WIRE 17 -1 (-7975 4375)(-8475 4375);
FORCEPROP 2 LAST SIG_NAME M_C_CPU0_SA_CB<7:0>
J 0
(-8475 4385);
DISPLAY 0.489362 (-8475 4385);
WIRE 17 -1 (-7975 4150)(-7975 4200);
WIRE 17 -1 (-7975 4100)(-7975 4150);
WIRE 17 -1 (-7975 4050)(-7975 4100);
WIRE 17 -1 (-7975 4000)(-7975 4050);
WIRE 17 -1 (-7975 3900)(-7975 3850);
WIRE 17 -1 (-7975 3900)(-7975 3925);
WIRE 17 -1 (-7975 3800)(-7975 3850);
WIRE 17 -1 (-7975 3800)(-7975 3750);
WIRE 17 -1 (-7975 3925)(-8475 3925);
FORCEPROP 2 LAST SIG_NAME M_C_CPU0_SB_CB<7:0>
J 0
(-8475 3935);
DISPLAY 0.489362 (-8475 3935);
WIRE 17 -1 (-7975 5450)(-7975 5500);
WIRE 17 -1 (-7975 5500)(-7975 5550);
WIRE 17 -1 (-7975 5550)(-7975 5600);
WIRE 17 -1 (-7975 5600)(-7975 5650);
WIRE 17 -1 (-7975 5650)(-7975 5700);
WIRE 17 -1 (-7975 5700)(-7975 5750);
WIRE 17 -1 (-7975 5750)(-7975 5775);
WIRE 17 -1 (-7975 5775)(-8475 5775);
FORCEPROP 2 LAST SIG_NAME M_C_CPU0_SA_CA<6:0>
J 0
(-8475 5785);
DISPLAY 0.489362 (-8475 5785);
WIRE 17 -1 (-7975 5050)(-7975 5100);
WIRE 17 -1 (-7975 5100)(-7975 5150);
WIRE 17 -1 (-7975 5150)(-7975 5200);
WIRE 17 -1 (-7975 5200)(-7975 5250);
WIRE 17 -1 (-7975 5250)(-7975 5300);
WIRE 17 -1 (-7975 5300)(-7975 5350);
WIRE 17 -1 (-7975 5350)(-7975 5375);
WIRE 17 -1 (-7975 5375)(-8475 5375);
FORCEPROP 2 LAST SIG_NAME M_C_CPU0_SB_CA<6:0>
J 0
(-8475 5385);
DISPLAY 0.489362 (-8475 5385);
WIRE 17 -1 (-7975 3700)(-7975 3750);
WIRE 17 -1 (-7975 3650)(-7975 3700);
WIRE 17 -1 (-7975 3600)(-7975 3650);
WIRE 17 -1 (-7975 3550)(-7975 3600);
WIRE 17 -1 (-6175 5600)(-6175 5550);
WIRE 17 -1 (-6175 5550)(-6175 5500);
WIRE 17 -1 (-6175 5500)(-6175 5450);
WIRE 17 -1 (-6175 5450)(-6175 5400);
WIRE 17 -1 (-6175 5400)(-6175 5350);
WIRE 17 -1 (-6175 5350)(-6175 5300);
WIRE 17 -1 (-6175 5300)(-6175 5250);
WIRE 17 -1 (-6175 5250)(-6175 5200);
WIRE 17 -1 (-6175 5200)(-6175 5150);
WIRE 17 -1 (-6175 5150)(-6175 5100);
WIRE 17 -1 (-6175 5100)(-6175 5050);
WIRE 17 -1 (-6175 5050)(-6175 5000);
WIRE 17 -1 (-6175 4950)(-6175 5000);
WIRE 17 -1 (-6175 4900)(-6175 4950);
WIRE 17 -1 (-6175 4850)(-6175 4900);
WIRE 17 -1 (-6175 4800)(-6175 4850);
WIRE 17 -1 (-6175 4800)(-6175 4750);
WIRE 17 -1 (-6175 4750)(-6175 4700);
WIRE 17 -1 (-6175 4700)(-6175 4650);
WIRE 17 -1 (-6175 4650)(-6175 4600);
WIRE 17 -1 (-6175 4600)(-6175 4550);
WIRE 17 -1 (-6175 4550)(-6175 4500);
WIRE 17 -1 (-6175 4500)(-6175 4450);
WIRE 17 -1 (-6175 4450)(-6175 4400);
WIRE 17 -1 (-6175 4350)(-6175 4400);
WIRE 17 -1 (-6175 4300)(-6175 4350);
WIRE 17 -1 (-6175 4250)(-6175 4300);
WIRE 17 -1 (-6175 4200)(-6175 4250);
WIRE 17 -1 (-6175 4100)(-6175 4050);
WIRE 17 -1 (-6175 4125)(-6175 4100);
WIRE 17 -1 (-6175 4050)(-6175 4000);
WIRE 17 -1 (-6175 4000)(-6175 3950);
WIRE 17 -1 (-6175 4125)(-5725 4125);
FORCEPROP 2 LAST SIG_NAME M_C_CPU0_SB_DQ<31:0>
J 2
(-5725 4135);
DISPLAY 0.489362 (-5725 4135);
WIRE 17 -1 (-6175 3950)(-6175 3900);
WIRE 17 -1 (-6175 3900)(-6175 3850);
WIRE 17 -1 (-6175 3850)(-6175 3800);
WIRE 17 -1 (-6175 3800)(-6175 3750);
WIRE 17 -1 (-6175 3750)(-6175 3700);
WIRE 17 -1 (-6175 3700)(-6175 3650);
WIRE 17 -1 (-6175 3650)(-6175 3600);
WIRE 17 -1 (-6175 3600)(-6175 3550);
WIRE 17 -1 (-6175 3550)(-6175 3500);
WIRE 17 -1 (-6175 3500)(-6175 3450);
WIRE 17 -1 (-6175 3450)(-6175 3400);
WIRE 17 -1 (-6175 3400)(-6175 3350);
WIRE 17 -1 (-6175 3300)(-6175 3350);
WIRE 17 -1 (-6175 3250)(-6175 3300);
WIRE 17 -1 (-6175 3200)(-6175 3250);
WIRE 17 -1 (-6175 3150)(-6175 3200);
WIRE 17 -1 (-6175 3150)(-6175 3100);
WIRE 17 -1 (-6175 3100)(-6175 3050);
WIRE 17 -1 (-6175 3050)(-6175 3000);
WIRE 17 -1 (-6175 3000)(-6175 2950);
WIRE 17 -1 (-6175 2950)(-6175 2900);
WIRE 17 -1 (-6175 2900)(-6175 2850);
WIRE 17 -1 (-6175 2850)(-6175 2800);
WIRE 17 -1 (-6175 2800)(-6175 2750);
WIRE 17 -1 (-6175 2700)(-6175 2750);
WIRE 17 -1 (-6175 2650)(-6175 2700);
WIRE 17 -1 (-6175 2600)(-6175 2650);
WIRE 17 -1 (-6175 2550)(-6175 2600);
WIRE 17 -1 (-3475 4725)(-3475 4625);
WIRE 17 -1 (-3475 4825)(-3475 4725);
WIRE 17 -1 (-3475 4625)(-3475 4525);
WIRE 17 -1 (-3475 4425)(-3475 4525);
WIRE 17 -1 (-3475 4925)(-3475 4825);
WIRE 17 -1 (-3475 4950)(-3475 4925);
WIRE 17 -1 (-3475 4325)(-3475 4425);
WIRE 17 -1 (-3475 4225)(-3475 4325);
WIRE 17 -1 (-3475 4950)(-2775 4950);
FORCEPROP 2 LAST SIG_NAME M_C_CPU0_SA_DQS_DN<9:0>
J 0
(-3410 4960);
DISPLAY 0.489362 (-3410 4960);
WIRE 17 -1 (-3675 4675)(-3675 4575);
WIRE 17 -1 (-3675 4775)(-3675 4675);
WIRE 17 -1 (-3675 4475)(-3675 4575);
WIRE 17 -1 (-3675 4375)(-3675 4475);
WIRE 17 -1 (-3675 4875)(-3675 4775);
WIRE 17 -1 (-3675 4975)(-3675 4875);
WIRE 17 -1 (-3675 4275)(-3675 4375);
WIRE 17 -1 (-3675 4275)(-3675 4175);
WIRE 17 -1 (-3675 5000)(-3675 4975);
WIRE 17 -1 (-3675 5000)(-2775 5000);
FORCEPROP 2 LAST SIG_NAME M_C_CPU0_SA_DQS_DP<9:0>
J 0
(-3410 5010);
DISPLAY 0.489362 (-3410 5010);
WIRE 17 -1 (-3675 3825)(-3675 3725);
WIRE 17 -1 (-3675 3925)(-3675 3825);
WIRE 17 -1 (-3675 3725)(-3675 3625);
WIRE 17 -1 (-3675 3625)(-3675 3525);
WIRE 17 -1 (-3675 3950)(-3675 3925);
WIRE 17 -1 (-3675 3950)(-2775 3950);
FORCEPROP 2 LAST SIG_NAME M_C_CPU0_SB_DQS_DP<9:0>
J 0
(-3410 3960);
DISPLAY 0.489362 (-3410 3960);
WIRE 17 -1 (-3475 3775)(-3475 3675);
WIRE 17 -1 (-3475 3875)(-3475 3775);
WIRE 17 -1 (-3475 3675)(-3475 3575);
WIRE 17 -1 (-3475 3575)(-3475 3475);
WIRE 17 -1 (-3475 3900)(-3475 3875);
WIRE 17 -1 (-3475 3900)(-2775 3900);
FORCEPROP 2 LAST SIG_NAME M_C_CPU0_SB_DQS_DN<9:0>
J 0
(-3410 3910);
DISPLAY 0.489362 (-3410 3910);
WIRE 17 -1 (-3675 3425)(-3675 3525);
WIRE 17 -1 (-3675 3325)(-3675 3425);
WIRE 17 -1 (-3675 3225)(-3675 3325);
WIRE 17 -1 (-3475 4125)(-3475 4025);
WIRE 17 -1 (-3475 4225)(-3475 4125);
WIRE 17 -1 (-3675 4175)(-3675 4075);
WIRE 17 -1 (-3475 3075)(-3475 2975);
WIRE 17 -1 (-3475 3175)(-3475 3075);
WIRE 17 -1 (-3475 3175)(-3475 3275);
WIRE 17 -1 (-3475 3275)(-3475 3375);
WIRE 17 -1 (-3475 3375)(-3475 3475);
WIRE 17 -1 (-3675 3125)(-3675 3025);
WIRE 17 -1 (-3675 3225)(-3675 3125);
WIRE 16 -1 (-6625 1400)(-6625 1475);
WIRE 16 -1 (-8925 3350)(-8925 3425);
WIRE 16 -1 (-8550 2725)(-8550 2750);
WIRE 16 -1 (-7675 3175)(-8475 3175);
FORCEPROP 2 LAST SIG_NAME I3C_SPD_DDRAF_CPU0_SDA
J 0
(-8485 3185);
DISPLAY 0.489362 (-8485 3185);
WIRE 16 -1 (-7775 3125)(-7775 3025);
WIRE 16 -1 (-7675 3125)(-7775 3125);
FORCEPROP 2 LAST SIG_NAME I3C_SPD_DDRC_CPU0_SCL
J 0
(-8160 3135);
DISPLAY 0.446809 (-8160 3135);
FORCEPROP 2 LASTPROP $XRERR UNIQUE?
J 0
(-8400 3135);
DISPLAY 0.638298 (-8400 3135);
PAINT MONO (-8400 3135);
DISPLAY INVISIBLE (-8400 3135);
WIRE 16 -1 (-7775 3025)(-7850 3025);
WIRE 16 -1 (-8050 3025)(-8475 3025);
FORCEPROP 2 LAST SIG_NAME I3C_SPD_DDRAF_CPU0_SCL
J 0
(-8535 3035);
DISPLAY 0.489362 (-8535 3035);
WIRE 16 -1 (-8350 2475)(-8550 2475);
WIRE 16 -1 (-8350 2475)(-8350 2875);
WIRE 16 -1 (-8550 2525)(-8550 2475);
WIRE 16 -1 (-8550 2475)(-8575 2475);
WIRE 16 -1 (-7675 2875)(-8350 2875);
FORCEPROP 2 LAST SIG_NAME PWRGD_CHC_CPU0_DIMM
J 0
(-8275 2885);
DISPLAY 0.489362 (-8275 2885);
FORCEPROP 2 LASTPROP $XRERR UNIQUE?
J 0
(-8515 2885);
DISPLAY 0.638298 (-8515 2885);
PAINT MONO (-8515 2885);
DISPLAY INVISIBLE (-8515 2885);
WIRE 16 -1 (-7675 3225)(-8475 3225);
FORCEPROP 2 LAST SIG_NAME PD_CHC_CPU0_DIMM_SAA
J 0
(-8475 3235);
DISPLAY 0.489362 (-8475 3235);
WIRE 16 -1 (-8800 3275)(-7675 3275);
WIRE 16 -1 (-8800 3700)(-8800 3275);
WIRE 16 -1 (-8800 3725)(-8800 3700);
WIRE 16 -1 (-8925 3700)(-8800 3700);
WIRE 16 -1 (-8925 3625)(-8925 3700);
WIRE 16 -1 (-7675 2725)(-8275 2725);
FORCEPROP 2 LAST SIG_NAME TP_CHC_CPU0_DIMM_RFU_5
J 0
(-8275 2735);
DISPLAY 0.489362 (-8275 2735);
FORCEPROP 2 LASTPROP $XRERR UNIQUE?
J 0
(-8515 2725);
DISPLAY 0.638298 (-8515 2725);
PAINT MONO (-8515 2725);
DISPLAY INVISIBLE (-8515 2725);
WIRE 16 -1 (-7675 2675)(-8275 2675);
FORCEPROP 2 LAST SIG_NAME TP_CHC_CPU0_DIMM_RFU_4
J 0
(-8275 2685);
DISPLAY 0.489362 (-8275 2685);
FORCEPROP 2 LASTPROP $XRERR UNIQUE?
J 0
(-8515 2675);
DISPLAY 0.638298 (-8515 2675);
PAINT MONO (-8515 2675);
DISPLAY INVISIBLE (-8515 2675);
WIRE 16 -1 (-7675 2625)(-8275 2625);
FORCEPROP 2 LAST SIG_NAME TP_CHC_CPU0_DIMM_RFU_3
J 0
(-8275 2635);
DISPLAY 0.489362 (-8275 2635);
FORCEPROP 2 LASTPROP $XRERR UNIQUE?
J 0
(-8515 2625);
DISPLAY 0.638298 (-8515 2625);
PAINT MONO (-8515 2625);
DISPLAY INVISIBLE (-8515 2625);
WIRE 16 -1 (-7675 2775)(-8275 2775);
FORCEPROP 2 LAST SIG_NAME TP_CHC_CPU0_DIMM_RFU_6
J 0
(-8275 2785);
DISPLAY 0.489362 (-8275 2785);
FORCEPROP 2 LASTPROP $XRERR UNIQUE?
J 0
(-8515 2775);
DISPLAY 0.638298 (-8515 2775);
PAINT MONO (-8515 2775);
DISPLAY INVISIBLE (-8515 2775);
WIRE 16 -1 (-2000 5550)(-2300 5550);
WIRE 16 -1 (-2300 5550)(-2300 5500);
WIRE 16 -1 (-2000 5500)(-2300 5500);
WIRE 16 -1 (-2300 5500)(-2300 5450);
WIRE 16 -1 (-2000 5450)(-2300 5450);
WIRE 16 -1 (-2300 5450)(-2300 5400);
WIRE 16 -1 (-2000 5400)(-2300 5400);
WIRE 16 -1 (-2300 5400)(-2300 5350);
WIRE 16 -1 (-2000 5350)(-2300 5350);
WIRE 16 -1 (-2300 5350)(-2300 5300);
WIRE 16 -1 (-2000 5300)(-2300 5300);
WIRE 16 -1 (-2300 5300)(-2300 5250);
WIRE 16 -1 (-2000 5250)(-2300 5250);
WIRE 16 -1 (-2300 5250)(-2300 5200);
WIRE 16 -1 (-2000 5200)(-2300 5200);
WIRE 16 -1 (-2300 5200)(-2300 5150);
WIRE 16 -1 (-2000 5150)(-2300 5150);
WIRE 16 -1 (-2300 5150)(-2300 5100);
WIRE 16 -1 (-2000 5100)(-2300 5100);
WIRE 16 -1 (-2300 5100)(-2300 5050);
WIRE 16 -1 (-2000 5050)(-2300 5050);
WIRE 16 -1 (-2300 5050)(-2300 5000);
WIRE 16 -1 (-2000 5000)(-2300 5000);
WIRE 16 -1 (-2300 5000)(-2300 4950);
WIRE 16 -1 (-2000 4950)(-2300 4950);
WIRE 16 -1 (-2300 4950)(-2300 4900);
WIRE 16 -1 (-2000 4900)(-2300 4900);
WIRE 16 -1 (-2300 4900)(-2300 4850);
WIRE 16 -1 (-2000 4850)(-2300 4850);
WIRE 16 -1 (-2300 4850)(-2300 4800);
WIRE 16 -1 (-2000 4800)(-2300 4800);
WIRE 16 -1 (-2300 4800)(-2300 4750);
WIRE 16 -1 (-2000 4750)(-2300 4750);
WIRE 16 -1 (-2300 4750)(-2300 4700);
WIRE 16 -1 (-2000 4700)(-2300 4700);
WIRE 16 -1 (-2300 4700)(-2300 4650);
WIRE 16 -1 (-2000 4650)(-2300 4650);
WIRE 16 -1 (-2300 4650)(-2300 4600);
WIRE 16 -1 (-2000 4600)(-2300 4600);
WIRE 16 -1 (-2300 4600)(-2300 4550);
WIRE 16 -1 (-2000 4550)(-2300 4550);
WIRE 16 -1 (-2300 4550)(-2300 4500);
WIRE 16 -1 (-2000 4500)(-2300 4500);
WIRE 16 -1 (-2300 4500)(-2300 4450);
WIRE 16 -1 (-2000 4450)(-2300 4450);
WIRE 16 -1 (-2300 4450)(-2300 4400);
WIRE 16 -1 (-2000 4400)(-2300 4400);
WIRE 16 -1 (-2300 4400)(-2300 4350);
WIRE 16 -1 (-2000 4350)(-2300 4350);
WIRE 16 -1 (-2300 4350)(-2300 4300);
WIRE 16 -1 (-2000 4300)(-2300 4300);
WIRE 16 -1 (-2300 4300)(-2300 4250);
WIRE 16 -1 (-2000 4250)(-2300 4250);
WIRE 16 -1 (-2300 4250)(-2300 4200);
WIRE 16 -1 (-2000 4200)(-2300 4200);
WIRE 16 -1 (-2300 4200)(-2300 4150);
WIRE 16 -1 (-2000 4150)(-2300 4150);
WIRE 16 -1 (-2300 4150)(-2300 4100);
WIRE 16 -1 (-2000 4100)(-2300 4100);
WIRE 16 -1 (-2300 4100)(-2300 4050);
WIRE 16 -1 (-2000 4050)(-2300 4050);
WIRE 16 -1 (-2300 4050)(-2300 4000);
WIRE 16 -1 (-2000 4000)(-2300 4000);
WIRE 16 -1 (-2300 4000)(-2300 3950);
WIRE 16 -1 (-2000 3950)(-2300 3950);
WIRE 16 -1 (-2300 3950)(-2300 3900);
WIRE 16 -1 (-2000 3900)(-2300 3900);
WIRE 16 -1 (-2300 3900)(-2300 3850);
WIRE 16 -1 (-2000 3850)(-2300 3850);
WIRE 16 -1 (-2300 3850)(-2300 3800);
WIRE 16 -1 (-2000 3800)(-2300 3800);
WIRE 16 -1 (-2300 3800)(-2300 3750);
WIRE 16 -1 (-2000 3750)(-2300 3750);
WIRE 16 -1 (-2300 3750)(-2300 3700);
WIRE 16 -1 (-2000 3700)(-2300 3700);
WIRE 16 -1 (-2300 3700)(-2300 3650);
WIRE 16 -1 (-2000 3650)(-2300 3650);
WIRE 16 -1 (-2300 3650)(-2300 3600);
WIRE 16 -1 (-2000 3600)(-2300 3600);
WIRE 16 -1 (-2300 3600)(-2300 3550);
WIRE 16 -1 (-2000 3550)(-2300 3550);
WIRE 16 -1 (-2300 3550)(-2300 3500);
WIRE 16 -1 (-2000 3500)(-2300 3500);
WIRE 16 -1 (-2300 3500)(-2300 3450);
WIRE 16 -1 (-2000 3450)(-2300 3450);
WIRE 16 -1 (-2300 3450)(-2300 3400);
WIRE 16 -1 (-2000 3400)(-2300 3400);
WIRE 16 -1 (-2300 3400)(-2300 3350);
WIRE 16 -1 (-2000 3350)(-2300 3350);
WIRE 16 -1 (-2300 3350)(-2300 3300);
WIRE 16 -1 (-2000 3300)(-2300 3300);
WIRE 16 -1 (-2300 3300)(-2300 3250);
WIRE 16 -1 (-2000 3250)(-2300 3250);
WIRE 16 -1 (-2300 3250)(-2300 3200);
WIRE 16 -1 (-2000 3200)(-2300 3200);
WIRE 16 -1 (-2300 3200)(-2300 3150);
WIRE 16 -1 (-2000 3150)(-2300 3150);
WIRE 16 -1 (-2300 3150)(-2300 3100);
WIRE 16 -1 (-2000 3100)(-2300 3100);
WIRE 16 -1 (-2300 3100)(-2300 3050);
WIRE 16 -1 (-2000 3050)(-2300 3050);
WIRE 16 -1 (-2300 3050)(-2300 3000);
WIRE 16 -1 (-2000 3000)(-2300 3000);
WIRE 16 -1 (-2300 3000)(-2300 2950);
WIRE 16 -1 (-2000 2950)(-2300 2950);
WIRE 16 -1 (-2300 2950)(-2300 2900);
WIRE 16 -1 (-2000 2900)(-2300 2900);
WIRE 16 -1 (-2300 2900)(-2300 2850);
WIRE 16 -1 (-2000 2850)(-2300 2850);
WIRE 16 -1 (-2300 2850)(-2300 2800);
WIRE 16 -1 (-2000 2800)(-2300 2800);
WIRE 16 -1 (-2300 2800)(-2300 2750);
WIRE 16 -1 (-2000 2750)(-2300 2750);
WIRE 16 -1 (-2300 2750)(-2300 2700);
WIRE 16 -1 (-2000 2700)(-2300 2700);
WIRE 16 -1 (-2300 2700)(-2300 2650);
WIRE 16 -1 (-2000 2650)(-2300 2650);
WIRE 16 -1 (-2300 2650)(-2300 2600);
WIRE 16 -1 (-2000 2600)(-2300 2600);
WIRE 16 -1 (-2300 2600)(-2300 2550);
WIRE 16 -1 (-2000 2550)(-2300 2550);
WIRE 16 -1 (-2300 2550)(-2300 2500);
WIRE 16 -1 (-2300 2500)(-2300 2450);
WIRE 16 -1 (-2000 2500)(-2300 2500);
WIRE 16 -1 (-2000 2450)(-2300 2450);
WIRE 16 -1 (-2300 2450)(-2300 2350);
WIRE 16 -1 (-2425 5925)(-3000 5925);
WIRE 16 -1 (-2425 5925)(-2425 6050);
WIRE 16 -1 (-3000 5925)(-3000 6050);
WIRE 16 -1 (-3000 5925)(-3000 5850);
WIRE 16 -1 (-2000 5600)(-2300 5600);
WIRE 16 -1 (-2300 5600)(-2300 5650);
WIRE 16 -1 (-2000 5650)(-2300 5650);
WIRE 16 -1 (-2300 5650)(-2300 5700);
WIRE 16 -1 (-2000 5700)(-2300 5700);
WIRE 16 -1 (-2300 5700)(-2300 6350);
WIRE 16 -1 (-2425 6350)(-2300 6350);
WIRE 16 -1 (-2425 6350)(-3000 6350);
WIRE 16 -1 (-2425 6350)(-2425 6250);
WIRE 16 -1 (-3000 6350)(-3000 6425);
WIRE 16 -1 (-3000 6250)(-3000 6350);
WIRE 16 -1 (-500 5700)(-500 5650);
WIRE 16 -1 (-500 5700)(-800 5700);
WIRE 16 -1 (-500 5650)(-500 5600);
WIRE 16 -1 (-500 5650)(-800 5650);
WIRE 16 -1 (-500 5600)(-500 5550);
WIRE 16 -1 (-500 5600)(-800 5600);
WIRE 16 -1 (-500 5550)(-500 5500);
WIRE 16 -1 (-500 5550)(-800 5550);
WIRE 16 -1 (-500 5500)(-500 5450);
WIRE 16 -1 (-500 5500)(-800 5500);
WIRE 16 -1 (-500 5450)(-500 5400);
WIRE 16 -1 (-500 5450)(-800 5450);
WIRE 16 -1 (-500 5400)(-500 5350);
WIRE 16 -1 (-500 5400)(-800 5400);
WIRE 16 -1 (-500 5350)(-500 5300);
WIRE 16 -1 (-500 5350)(-800 5350);
WIRE 16 -1 (-500 5300)(-500 5250);
WIRE 16 -1 (-500 5300)(-800 5300);
WIRE 16 -1 (-500 5250)(-500 5200);
WIRE 16 -1 (-500 5250)(-800 5250);
WIRE 16 -1 (-500 5200)(-500 5150);
WIRE 16 -1 (-500 5200)(-800 5200);
WIRE 16 -1 (-500 5150)(-800 5150);
WIRE 16 -1 (-500 5150)(-500 5100);
WIRE 16 -1 (-500 5100)(-500 5050);
WIRE 16 -1 (-500 5100)(-800 5100);
WIRE 16 -1 (-500 5050)(-500 5000);
WIRE 16 -1 (-500 5050)(-800 5050);
WIRE 16 -1 (-500 5000)(-500 4950);
WIRE 16 -1 (-500 5000)(-800 5000);
WIRE 16 -1 (-500 4950)(-500 4900);
WIRE 16 -1 (-500 4950)(-800 4950);
WIRE 16 -1 (-500 4900)(-500 4850);
WIRE 16 -1 (-500 4900)(-800 4900);
WIRE 16 -1 (-500 4850)(-500 4800);
WIRE 16 -1 (-500 4850)(-800 4850);
WIRE 16 -1 (-500 4800)(-500 4750);
WIRE 16 -1 (-500 4800)(-800 4800);
WIRE 16 -1 (-500 4750)(-500 4700);
WIRE 16 -1 (-500 4750)(-800 4750);
WIRE 16 -1 (-500 4700)(-500 4650);
WIRE 16 -1 (-500 4700)(-800 4700);
WIRE 16 -1 (-500 4650)(-500 4600);
WIRE 16 -1 (-500 4650)(-800 4650);
WIRE 16 -1 (-500 4600)(-500 4550);
WIRE 16 -1 (-500 4600)(-800 4600);
WIRE 16 -1 (-500 4550)(-500 4500);
WIRE 16 -1 (-500 4550)(-800 4550);
WIRE 16 -1 (-500 4500)(-500 4450);
WIRE 16 -1 (-500 4500)(-800 4500);
WIRE 16 -1 (-500 4450)(-500 4400);
WIRE 16 -1 (-500 4450)(-800 4450);
WIRE 16 -1 (-500 4400)(-500 4350);
WIRE 16 -1 (-500 4400)(-800 4400);
WIRE 16 -1 (-500 4350)(-500 4300);
WIRE 16 -1 (-500 4350)(-800 4350);
WIRE 16 -1 (-500 4300)(-500 4250);
WIRE 16 -1 (-500 4300)(-800 4300);
WIRE 16 -1 (-500 4250)(-500 4200);
WIRE 16 -1 (-500 4250)(-800 4250);
WIRE 16 -1 (-500 4200)(-500 4150);
WIRE 16 -1 (-500 4200)(-800 4200);
WIRE 16 -1 (-500 4150)(-500 4100);
WIRE 16 -1 (-500 4150)(-800 4150);
WIRE 16 -1 (-500 4100)(-800 4100);
WIRE 16 -1 (-500 4100)(-500 4050);
WIRE 16 -1 (-500 4050)(-500 4000);
WIRE 16 -1 (-500 4050)(-800 4050);
WIRE 16 -1 (-500 4000)(-500 3950);
WIRE 16 -1 (-500 4000)(-800 4000);
WIRE 16 -1 (-500 3950)(-500 3900);
WIRE 16 -1 (-500 3950)(-800 3950);
WIRE 16 -1 (-500 3900)(-500 3850);
WIRE 16 -1 (-500 3900)(-800 3900);
WIRE 16 -1 (-500 3850)(-500 3800);
WIRE 16 -1 (-500 3850)(-800 3850);
WIRE 16 -1 (-500 3800)(-500 3750);
WIRE 16 -1 (-500 3800)(-800 3800);
WIRE 16 -1 (-500 3750)(-500 3700);
WIRE 16 -1 (-500 3750)(-800 3750);
WIRE 16 -1 (-500 3700)(-500 3650);
WIRE 16 -1 (-500 3700)(-800 3700);
WIRE 16 -1 (-500 3650)(-500 3600);
WIRE 16 -1 (-500 3650)(-800 3650);
WIRE 16 -1 (-500 3600)(-500 3550);
WIRE 16 -1 (-500 3600)(-800 3600);
WIRE 16 -1 (-500 3550)(-500 3500);
WIRE 16 -1 (-500 3550)(-800 3550);
WIRE 16 -1 (-500 3500)(-500 3450);
WIRE 16 -1 (-500 3500)(-800 3500);
WIRE 16 -1 (-500 3450)(-500 3400);
WIRE 16 -1 (-500 3450)(-800 3450);
WIRE 16 -1 (-500 3400)(-500 3350);
WIRE 16 -1 (-500 3400)(-800 3400);
WIRE 16 -1 (-500 3350)(-500 3300);
WIRE 16 -1 (-500 3350)(-800 3350);
WIRE 16 -1 (-500 3300)(-500 3250);
WIRE 16 -1 (-500 3300)(-800 3300);
WIRE 16 -1 (-500 3250)(-500 3200);
WIRE 16 -1 (-500 3250)(-800 3250);
WIRE 16 -1 (-500 3200)(-500 3150);
WIRE 16 -1 (-500 3200)(-800 3200);
WIRE 16 -1 (-500 3150)(-500 3100);
WIRE 16 -1 (-500 3150)(-800 3150);
WIRE 16 -1 (-500 3100)(-800 3100);
WIRE 16 -1 (-500 3100)(-500 3050);
WIRE 16 -1 (-500 3050)(-500 3000);
WIRE 16 -1 (-500 3050)(-800 3050);
WIRE 16 -1 (-500 3000)(-500 2950);
WIRE 16 -1 (-500 3000)(-800 3000);
WIRE 16 -1 (-500 2950)(-500 2900);
WIRE 16 -1 (-500 2950)(-800 2950);
WIRE 16 -1 (-500 2900)(-500 2850);
WIRE 16 -1 (-500 2900)(-800 2900);
WIRE 16 -1 (-500 2850)(-500 2800);
WIRE 16 -1 (-500 2850)(-800 2850);
WIRE 16 -1 (-500 2800)(-500 2750);
WIRE 16 -1 (-500 2800)(-800 2800);
WIRE 16 -1 (-500 2750)(-500 2700);
WIRE 16 -1 (-500 2750)(-800 2750);
WIRE 16 -1 (-500 2700)(-500 2650);
WIRE 16 -1 (-500 2700)(-800 2700);
WIRE 16 -1 (-500 2650)(-500 2600);
WIRE 16 -1 (-500 2650)(-800 2650);
WIRE 16 -1 (-500 2600)(-500 2550);
WIRE 16 -1 (-500 2600)(-800 2600);
WIRE 16 -1 (-500 2550)(-500 2450);
WIRE 16 -1 (-500 2550)(-800 2550);
WIRE 16 -1 (-500 2450)(-500 2400);
WIRE 16 -1 (-500 2450)(-800 2450);
WIRE 16 -1 (-500 2400)(-500 2350);
WIRE 16 -1 (-500 2400)(-800 2400);
WIRE 16 -1 (-500 2350)(-500 2150);
WIRE 16 -1 (-500 2350)(-800 2350);
WIRE 16 -1 (-3925 3900)(-3775 3900);
WIRE 16 -1 (-3925 3850)(-3575 3850);
WIRE 16 -1 (-3925 4950)(-3775 4950);
WIRE 16 -1 (-3925 4900)(-3575 4900);
WIRE 16 -1 (-3775 4850)(-3925 4850);
WIRE 16 -1 (-3925 4800)(-3575 4800);
WIRE 16 -1 (-3925 3650)(-3575 3650);
WIRE 16 -1 (-3775 4750)(-3925 4750);
WIRE 16 -1 (-3775 3600)(-3925 3600);
WIRE 16 -1 (-3925 3550)(-3575 3550);
WIRE 16 -1 (-3925 4600)(-3575 4600);
WIRE 16 -1 (-3925 3500)(-3775 3500);
WIRE 16 -1 (-3925 3450)(-3575 3450);
WIRE 16 -1 (-3925 4550)(-3775 4550);
WIRE 16 -1 (-3925 4500)(-3575 4500);
WIRE 16 -1 (-3775 3400)(-3925 3400);
WIRE 16 -1 (-3925 3350)(-3575 3350);
WIRE 16 -1 (-3775 4450)(-3925 4450);
WIRE 16 -1 (-3925 4400)(-3575 4400);
WIRE 16 -1 (-3775 3300)(-3925 3300);
WIRE 16 -1 (-3925 3250)(-3575 3250);
WIRE 16 -1 (-3775 4350)(-3925 4350);
WIRE 16 -1 (-3925 4300)(-3575 4300);
WIRE 16 -1 (-3775 3200)(-3925 3200);
WIRE 16 -1 (-3925 3150)(-3575 3150);
WIRE 16 -1 (-3775 4250)(-3925 4250);
WIRE 16 -1 (-3925 4200)(-3575 4200);
WIRE 16 -1 (-3925 3100)(-3775 3100);
WIRE 16 -1 (-3925 3050)(-3575 3050);
WIRE 16 -1 (-3925 4150)(-3775 4150);
WIRE 16 -1 (-3925 4100)(-3575 4100);
WIRE 16 -1 (-3775 3000)(-3925 3000);
WIRE 16 -1 (-3925 2950)(-3575 2950);
WIRE 16 -1 (-3775 4050)(-3925 4050);
WIRE 16 -1 (-3925 4000)(-3575 4000);
WIRE 16 -1 (-3775 3700)(-3925 3700);
WIRE 16 -1 (-3925 3750)(-3575 3750);
WIRE 16 -1 (-3775 3800)(-3925 3800);
WIRE 16 -1 (-3775 4650)(-3925 4650);
WIRE 16 -1 (-3925 4700)(-3575 4700);
WIRE 16 -1 (-6275 5175)(-6475 5175);
WIRE 16 -1 (-6275 5225)(-6475 5225);
WIRE 16 -1 (-6275 5275)(-6475 5275);
WIRE 16 -1 (-6475 5325)(-6275 5325);
WIRE 16 -1 (-6275 5375)(-6475 5375);
WIRE 16 -1 (-6475 5525)(-6275 5525);
WIRE 16 -1 (-6275 5575)(-6475 5575);
WIRE 16 -1 (-7675 2475)(-8275 2475);
FORCEPROP 2 LAST SIG_NAME TP_CHC_CPU0_DIMM_RFU_0
J 0
(-8275 2485);
DISPLAY 0.489362 (-8275 2485);
FORCEPROP 2 LASTPROP $XRERR UNIQUE?
J 0
(-8515 2475);
DISPLAY 0.638298 (-8515 2475);
PAINT MONO (-8515 2475);
DISPLAY INVISIBLE (-8515 2475);
WIRE 16 -1 (-7675 2525)(-8275 2525);
FORCEPROP 2 LAST SIG_NAME TP_CHC_CPU0_DIMM_RFU_1
J 0
(-8275 2535);
DISPLAY 0.489362 (-8275 2535);
FORCEPROP 2 LASTPROP $XRERR UNIQUE?
J 0
(-8515 2525);
DISPLAY 0.638298 (-8515 2525);
PAINT MONO (-8515 2525);
DISPLAY INVISIBLE (-8515 2525);
WIRE 16 -1 (-7675 2575)(-8275 2575);
FORCEPROP 2 LAST SIG_NAME TP_CHC_CPU0_DIMM_RFU_2
J 0
(-8275 2585);
DISPLAY 0.489362 (-8275 2585);
FORCEPROP 2 LASTPROP $XRERR UNIQUE?
J 0
(-8515 2575);
DISPLAY 0.638298 (-8515 2575);
PAINT MONO (-8515 2575);
DISPLAY INVISIBLE (-8515 2575);
WIRE 16 -1 (-7675 3425)(-8475 3425);
FORCEPROP 2 LAST SIG_NAME M_C_CPU0_RESET_N
J 0
(-8475 3435);
DISPLAY 0.489362 (-8475 3435);
WIRE 16 -1 (-7675 4875)(-8475 4875);
FORCEPROP 2 LAST SIG_NAME M_C_CPU0_SB_PAR
J 0
(-8475 4885);
DISPLAY 0.489362 (-8475 4885);
WIRE 16 -1 (-7675 4925)(-8475 4925);
FORCEPROP 2 LAST SIG_NAME M_C_CPU0_SA_PAR
J 0
(-8475 4935);
DISPLAY 0.489362 (-8475 4935);
WIRE 16 -1 (-7675 2275)(-8475 2275);
FORCEPROP 2 LAST SIG_NAME M_C_CPU0_SB_RSP<0>
J 0
(-8475 2285);
DISPLAY 0.489362 (-8475 2285);
WIRE 16 -1 (-7675 2325)(-8475 2325);
FORCEPROP 2 LAST SIG_NAME M_C_CPU0_SA_RSP<0>
J 0
(-8475 2335);
DISPLAY 0.489362 (-8475 2335);
WIRE 16 -1 (-6275 2525)(-6475 2525);
WIRE 16 -1 (-6275 2575)(-6475 2575);
WIRE 16 -1 (-6275 2625)(-6475 2625);
WIRE 16 -1 (-6475 2675)(-6275 2675);
WIRE 16 -1 (-6275 2725)(-6475 2725);
WIRE 16 -1 (-6275 2775)(-6475 2775);
WIRE 16 -1 (-6275 2825)(-6475 2825);
WIRE 16 -1 (-6475 2875)(-6275 2875);
WIRE 16 -1 (-6275 2925)(-6475 2925);
WIRE 16 -1 (-6275 2975)(-6475 2975);
WIRE 16 -1 (-6275 3025)(-6475 3025);
WIRE 16 -1 (-6475 3075)(-6275 3075);
WIRE 16 -1 (-6275 3125)(-6475 3125);
WIRE 16 -1 (-6275 3175)(-6475 3175);
WIRE 16 -1 (-6275 3225)(-6475 3225);
WIRE 16 -1 (-6475 3275)(-6275 3275);
WIRE 16 -1 (-6275 3325)(-6475 3325);
WIRE 16 -1 (-6275 3375)(-6475 3375);
WIRE 16 -1 (-6275 3425)(-6475 3425);
WIRE 16 -1 (-6475 3475)(-6275 3475);
WIRE 16 -1 (-6275 3525)(-6475 3525);
WIRE 16 -1 (-6275 3575)(-6475 3575);
WIRE 16 -1 (-6275 3625)(-6475 3625);
WIRE 16 -1 (-6475 3675)(-6275 3675);
WIRE 16 -1 (-6275 3725)(-6475 3725);
WIRE 16 -1 (-6275 3775)(-6475 3775);
WIRE 16 -1 (-6275 3825)(-6475 3825);
WIRE 16 -1 (-6475 3875)(-6275 3875);
WIRE 16 -1 (-6275 3925)(-6475 3925);
WIRE 16 -1 (-6275 3975)(-6475 3975);
WIRE 16 -1 (-6275 4025)(-6475 4025);
WIRE 16 -1 (-6475 4075)(-6275 4075);
WIRE 16 -1 (-6275 4175)(-6475 4175);
WIRE 16 -1 (-6275 4225)(-6475 4225);
WIRE 16 -1 (-6275 4275)(-6475 4275);
WIRE 16 -1 (-6475 4325)(-6275 4325);
WIRE 16 -1 (-6275 4375)(-6475 4375);
WIRE 16 -1 (-6275 4425)(-6475 4425);
WIRE 16 -1 (-6275 4475)(-6475 4475);
WIRE 16 -1 (-6475 4525)(-6275 4525);
WIRE 16 -1 (-6275 4575)(-6475 4575);
WIRE 16 -1 (-6275 4625)(-6475 4625);
WIRE 16 -1 (-6275 4675)(-6475 4675);
WIRE 16 -1 (-6475 4725)(-6275 4725);
WIRE 16 -1 (-6275 4775)(-6475 4775);
WIRE 16 -1 (-6275 4825)(-6475 4825);
WIRE 16 -1 (-6275 4875)(-6475 4875);
WIRE 16 -1 (-6475 4925)(-6275 4925);
WIRE 16 -1 (-6275 4975)(-6475 4975);
WIRE 16 -1 (-6275 5025)(-6475 5025);
WIRE 16 -1 (-6275 5075)(-6475 5075);
WIRE 16 -1 (-6475 5125)(-6275 5125);
WIRE 16 -1 (-6275 5425)(-6475 5425);
WIRE 16 -1 (-6275 5475)(-6475 5475);
WIRE 16 -1 (-6275 5625)(-6475 5625);
WIRE 16 -1 (-6275 5675)(-6475 5675);
WIRE 16 -1 (-7675 4625)(-8475 4625);
FORCEPROP 2 LAST SIG_NAME M_C_CPU0_SB_CS_N<1>
J 0
(-8475 4635);
DISPLAY 0.489362 (-8475 4635);
WIRE 16 -1 (-7675 4775)(-8475 4775);
FORCEPROP 2 LAST SIG_NAME M_C_CPU0_SA_CS_N<1>
J 0
(-8475 4785);
DISPLAY 0.489362 (-8475 4785);
WIRE 16 -1 (-7675 4575)(-8475 4575);
FORCEPROP 2 LAST SIG_NAME M_C_CPU0_SB_CS_N<0>
J 0
(-8475 4585);
DISPLAY 0.489362 (-8475 4585);
WIRE 16 -1 (-7675 4725)(-8475 4725);
FORCEPROP 2 LAST SIG_NAME M_C_CPU0_SA_CS_N<0>
J 0
(-8475 4735);
DISPLAY 0.489362 (-8475 4735);
WIRE 16 -1 (-7675 4475)(-8475 4475);
FORCEPROP 2 LAST SIG_NAME M_C_CPU0_CLK_DP<0>
J 0
(-8475 4485);
DISPLAY 0.489362 (-8475 4485);
WIRE 16 -1 (-7675 4425)(-8475 4425);
FORCEPROP 2 LAST SIG_NAME M_C_CPU0_CLK_DN<0>
J 0
(-8475 4435);
DISPLAY 0.489362 (-8475 4435);
WIRE 16 -1 (-7675 3525)(-7875 3525);
WIRE 16 -1 (-7675 3575)(-7875 3575);
WIRE 16 -1 (-7675 3625)(-7875 3625);
WIRE 16 -1 (-7675 3675)(-7875 3675);
WIRE 16 -1 (-7675 3725)(-7875 3725);
WIRE 16 -1 (-7675 3775)(-7875 3775);
WIRE 16 -1 (-7675 3825)(-7875 3825);
WIRE 16 -1 (-7675 3975)(-7875 3975);
WIRE 16 -1 (-7675 4075)(-7875 4075);
WIRE 16 -1 (-7675 4125)(-7875 4125);
WIRE 16 -1 (-7675 4225)(-7875 4225);
WIRE 16 -1 (-7675 4275)(-7875 4275);
WIRE 16 -1 (-7675 5325)(-7875 5325);
WIRE 16 -1 (-7675 5725)(-7875 5725);
WIRE 16 -1 (-7675 5275)(-7875 5275);
WIRE 16 -1 (-7675 5675)(-7875 5675);
WIRE 16 -1 (-7675 5225)(-7875 5225);
WIRE 16 -1 (-7675 5625)(-7875 5625);
WIRE 16 -1 (-7675 5175)(-7875 5175);
WIRE 16 -1 (-7675 5575)(-7875 5575);
WIRE 16 -1 (-7675 5125)(-7875 5125);
WIRE 16 -1 (-7675 5525)(-7875 5525);
WIRE 16 -1 (-7675 5075)(-7875 5075);
WIRE 16 -1 (-7675 5475)(-7875 5475);
WIRE 16 -1 (-7675 5025)(-7875 5025);
WIRE 16 -1 (-7675 5425)(-7875 5425);
WIRE 16 -1 (-7675 3375)(-8475 3375);
FORCEPROP 2 LAST SIG_NAME M_C_CPU0_ALERT_N
J 0
(-8475 3385);
DISPLAY 0.489362 (-8475 3385);
WIRE 16 -1 (-7675 3875)(-7875 3875);
WIRE 16 -1 (-7675 4025)(-7875 4025);
WIRE 16 -1 (-7675 4175)(-7875 4175);
WIRE 16 -1 (-7675 4325)(-7875 4325);
WIRE 16 -1 (-6475 5725)(-6275 5725);
WIRE 16 -1 (-9125 2475)(-8775 2475);
FORCEPROP 2 LAST SIG_NAME PWRGD_CHAF_CPU0
J 0
(-9135 2485);
DISPLAY 0.489362 (-9135 2485);
WIRE 16 -1 (-6625 1750)(-6625 1675);
WIRE 16 -1 (-6625 1750)(-7350 1750);
FORCEPROP 2 LAST SIG_NAME PD_CHC_CPU0_DIMM_SAA
J 0
(-7335 1760);
DISPLAY 0.489362 (-7335 1760);
DOT 1 (-2425 6350);
DOT 1 (-3000 6350);
DOT 1 (-3000 5925);
DOT 1 (-8550 2475);
DOT 1 (-8800 3700);
DOT 1 (-2300 5700);
DOT 1 (-500 5600);
DOT 1 (-500 5650);
DOT 1 (-500 5550);
DOT 1 (-500 5200);
DOT 1 (-500 5250);
DOT 1 (-500 5300);
DOT 1 (-500 5100);
DOT 1 (-500 5150);
DOT 1 (-500 4950);
DOT 1 (-500 5000);
DOT 1 (-500 5050);
DOT 1 (-500 4850);
DOT 1 (-500 4900);
DOT 1 (-500 4700);
DOT 1 (-500 4750);
DOT 1 (-500 4800);
DOT 1 (-500 4600);
DOT 1 (-500 4650);
DOT 1 (-2300 5500);
DOT 1 (-2300 5450);
DOT 1 (-2300 5400);
DOT 1 (-2300 5350);
DOT 1 (-2300 5250);
DOT 1 (-2300 5100);
DOT 1 (-2300 5150);
DOT 1 (-2300 4950);
DOT 1 (-2300 5000);
DOT 1 (-2300 5050);
DOT 1 (-2300 4900);
DOT 1 (-2300 4700);
DOT 1 (-2300 4750);
DOT 1 (-2300 4800);
DOT 1 (-2300 4600);
DOT 1 (-2300 4650);
DOT 1 (-500 4550);
DOT 1 (-2300 4550);
DOT 1 (-500 4500);
DOT 1 (-500 4450);
DOT 1 (-500 4350);
DOT 1 (-500 4400);
DOT 1 (-500 4300);
DOT 1 (-500 4250);
DOT 1 (-500 4200);
DOT 1 (-500 4100);
DOT 1 (-500 4050);
DOT 1 (-500 4150);
DOT 1 (-500 4000);
DOT 1 (-500 3950);
DOT 1 (-500 3800);
DOT 1 (-500 3850);
DOT 1 (-500 3900);
DOT 1 (-500 3750);
DOT 1 (-500 3700);
DOT 1 (-500 3600);
DOT 1 (-500 3550);
DOT 1 (-500 3650);
DOT 1 (-500 3450);
DOT 1 (-500 3500);
DOT 1 (-500 3400);
DOT 1 (-500 3350);
DOT 1 (-500 3300);
DOT 1 (-500 3200);
DOT 1 (-500 3250);
DOT 1 (-500 3150);
DOT 1 (-500 3050);
DOT 1 (-500 3100);
DOT 1 (-500 2900);
DOT 1 (-500 2950);
DOT 1 (-500 3000);
DOT 1 (-500 2850);
DOT 1 (-500 2800);
DOT 1 (-500 2650);
DOT 1 (-500 2700);
DOT 1 (-500 2750);
DOT 1 (-500 2550);
DOT 1 (-500 2600);
DOT 1 (-500 2450);
DOT 1 (-500 2400);
DOT 1 (-500 2350);
DOT 1 (-2300 4500);
DOT 1 (-2300 4450);
DOT 1 (-2300 4350);
DOT 1 (-2300 4400);
DOT 1 (-2300 4300);
DOT 1 (-2300 4250);
DOT 1 (-2300 4200);
DOT 1 (-2300 4100);
DOT 1 (-2300 4050);
DOT 1 (-2300 4150);
DOT 1 (-2300 4000);
DOT 1 (-2300 3950);
DOT 1 (-2300 3800);
DOT 1 (-2300 3850);
DOT 1 (-2300 3900);
DOT 1 (-2300 3750);
DOT 1 (-2300 3700);
DOT 1 (-2300 3650);
DOT 1 (-2300 3550);
DOT 1 (-2300 3600);
DOT 1 (-2300 3450);
DOT 1 (-2300 3500);
DOT 1 (-2300 3350);
DOT 1 (-2300 3300);
DOT 1 (-2300 3200);
DOT 1 (-2300 3250);
DOT 1 (-2300 3150);
DOT 1 (-2300 3050);
DOT 1 (-2300 3100);
DOT 1 (-2300 2900);
DOT 1 (-2300 2950);
DOT 1 (-2300 3000);
DOT 1 (-2300 2850);
DOT 1 (-2300 2800);
DOT 1 (-2300 2650);
DOT 1 (-2300 2700);
DOT 1 (-2300 2750);
DOT 1 (-2300 2550);
DOT 1 (-2300 2600);
DOT 1 (-2300 2500);
DOT 1 (-2300 2450);
DOT 1 (-2300 3400);
DOT 1 (-500 5500);
DOT 1 (-500 5450);
DOT 1 (-500 5400);
DOT 1 (-500 5350);
DOT 1 (-2300 4850);
DOT 1 (-2300 5200);
DOT 1 (-2300 5300);
DOT 1 (-2300 5650);
QUIT
